G04 ================== begin FILE IDENTIFICATION RECORD ==================*
G04 Layout Name:  t6mg_pdb_a_v02_0109_1330.brd*
G04 Film Name:    vcc*
G04 File Format:  Gerber RS274X*
G04 File Origin:  Cadence Allegro 16.3-S038*
G04 Origin Date:  Mon Jan 13 14:11:52 2014*
G04 *
G04 Layer:  DRAWING FORMAT/TITLE_BLOCK*
G04 Layer:  VIA CLASS/VCC*
G04 Layer:  PIN/VCC*
G04 Layer:  MANUFACTURING/PHOTOPLOT_OUTLINE*
G04 Layer:  ETCH/VCC*
G04 Layer:  DRAWING FORMAT/TITLE_DATA_VCC*
G04 *
G04 Offset:    (0.00 0.00)*
G04 Mirror:    No*
G04 Mode:      Negative*
G04 Rotation:  0*
G04 FullContactRelief:  No*
G04 UndefLineWidth:     6.00*
G04 ================== end FILE IDENTIFICATION RECORD ====================*
%FSLAX25Y25*MOIN*%
%IR0*IPPOS*OFA0.00000B0.00000*MIA0B0*SFA1.00000B1.00000*%
%ADD11C,.03*%
%ADD30C,.05*%
%ADD24C,.042*%
%ADD12C,.063*%
%ADD27C,.064*%
%ADD20C,.082*%
%ADD21C,.083*%
%ADD14C,.056*%
%ADD16C,.048*%
%ADD23C,.059*%
%ADD19C,.077*%
%AMMACRO13*
4,1,16,.02548,.01487,
.027675,.01022,
.029029,.005259,
.029501,.000138,
.029077,-.004987,
.027769,-.009961,
.025618,-.014631,
.02548,-.01487,
.03056,-.01996,
.033562,-.01435,
.035544,-.008304,
.036446,-.002006,
.03624,.004353,
.034934,.01058,
.032566,.016486,
.03056,.01996,
.02548,.01487,
90.*
4,1,16,.01487,-.02548,
.01022,-.027675,
.005259,-.029029,
.000138,-.029501,
-.004987,-.029077,
-.009961,-.027769,
-.014631,-.025618,
-.01487,-.02548,
-.01996,-.03056,
-.01435,-.033562,
-.008304,-.035544,
-.002006,-.036446,
.004353,-.03624,
.01058,-.034934,
.016486,-.032566,
.01996,-.03056,
.01487,-.02548,
90.*
4,1,16,-.02548,-.01487,
-.027675,-.01022,
-.029029,-.005259,
-.029501,-.000138,
-.029077,.004987,
-.027769,.009961,
-.025618,.014631,
-.02548,.01487,
-.03056,.01996,
-.033562,.01435,
-.035544,.008304,
-.036446,.002006,
-.03624,-.004353,
-.034934,-.01058,
-.032566,-.016486,
-.03056,-.01996,
-.02548,-.01487,
90.*
4,1,16,-.01487,.02548,
-.01022,.027675,
-.005259,.029029,
-.000138,.029501,
.004987,.029077,
.009961,.027769,
.014631,.025618,
.01487,.02548,
.01996,.03056,
.01435,.033562,
.008304,.035544,
.002006,.036446,
-.004353,.03624,
-.01058,.034934,
-.016486,.032566,
-.01996,.03056,
-.01487,.02548,
90.*
%
%ADD13MACRO13*%
%ADD34O,.235X.274*%
%ADD18C,.125*%
%ADD10C,.162*%
%ADD33C,.235*%
%ADD35C,.345*%
%ADD29C,.129*%
%ADD15C,.156*%
%AMMACRO17*
4,1,36,0.0,.013,
-.002257,.012803,
-.004446,.012216,
-.0065,.011258,
-.008356,.009959,
-.009959,.008356,
-.011258,.0065,
-.012216,.004446,
-.012803,.002257,
-.013,0.0,
-.012803,-.002257,
-.012216,-.004446,
-.011258,-.0065,
-.009959,-.008356,
-.008356,-.009959,
-.0065,-.011258,
-.004446,-.012216,
-.002257,-.012803,
0.0,-.013,
.002257,-.012803,
.004446,-.012216,
.0065,-.011258,
.008356,-.009959,
.009959,-.008356,
.011258,-.0065,
.012216,-.004446,
.012803,-.002257,
.013,0.0,
.012803,.002257,
.012216,.004446,
.011258,.0065,
.009959,.008356,
.008356,.009959,
.0065,.011258,
.004446,.012216,
.002257,.012803,
0.0,.013,
270.*
%
%ADD17MACRO17*%
%AMMACRO32*
4,1,36,0.0,.014,
.002431,.013787,
.004788,.013156,
.007,.012124,
.008999,.010725,
.010725,.008999,
.012124,.007,
.013156,.004788,
.013787,.002431,
.014,0.0,
.013787,-.002431,
.013156,-.004788,
.012124,-.007,
.010725,-.008999,
.008999,-.010725,
.007,-.012124,
.004788,-.013156,
.002431,-.013787,
0.0,-.014,
-.002431,-.013787,
-.004788,-.013156,
-.007,-.012124,
-.008999,-.010725,
-.010725,-.008999,
-.012124,-.007,
-.013156,-.004788,
-.013787,-.002431,
-.014,0.0,
-.013787,.002431,
-.013156,.004788,
-.012124,.007,
-.010725,.008999,
-.008999,.010725,
-.007,.012124,
-.004788,.013156,
-.002431,.013787,
0.0,.014,
180.*
%
%ADD32MACRO32*%
%ADD25C,.188*%
%AMMACRO26*
4,1,36,0.0,.004,
.000695,.003939,
.001368,.003759,
.002,.003464,
.002571,.003064,
.003064,.002571,
.003464,.002,
.003759,.001368,
.003939,.000695,
.004,0.0,
.003939,-.000695,
.003759,-.001368,
.003464,-.002,
.003064,-.002571,
.002571,-.003064,
.002,-.003464,
.001368,-.003759,
.000695,-.003939,
0.0,-.004,
-.000695,-.003939,
-.001368,-.003759,
-.002,-.003464,
-.002571,-.003064,
-.003064,-.002571,
-.003464,-.002,
-.003759,-.001368,
-.003939,-.000695,
-.004,0.0,
-.003939,.000695,
-.003759,.001368,
-.003464,.002,
-.003064,.002571,
-.002571,.003064,
-.002,.003464,
-.001368,.003759,
-.000695,.003939,
0.0,.004,
0.0*
%
%ADD26MACRO26*%
%AMMACRO28*
4,1,16,.02584,.01524,
.028094,.010521,
.029494,.005483,
.029998,.000278,
.029591,-.004935,
.028284,-.009999,
.026118,-.014758,
.02584,-.01524,
.03092,-.02032,
.033979,-.014642,
.036005,-.008519,
.036938,-.002138,
.036748,.004309,
.035441,.010625,
.033058,.016618,
.03092,.02032,
.02584,.01524,
270.*
4,1,16,.01524,-.02584,
.010521,-.028094,
.005483,-.029494,
.000278,-.029998,
-.004935,-.029591,
-.009999,-.028284,
-.014758,-.026118,
-.01524,-.02584,
-.02032,-.03092,
-.014642,-.033979,
-.008519,-.036005,
-.002138,-.036938,
.004309,-.036748,
.010625,-.035441,
.016618,-.033058,
.02032,-.03092,
.01524,-.02584,
270.*
4,1,16,-.02584,-.01524,
-.028094,-.010521,
-.029494,-.005483,
-.029998,-.000278,
-.029591,.004935,
-.028284,.009999,
-.026118,.014758,
-.02584,.01524,
-.03092,.02032,
-.033979,.014642,
-.036005,.008519,
-.036938,.002138,
-.036748,-.004309,
-.035441,-.010625,
-.033058,-.016618,
-.03092,-.02032,
-.02584,-.01524,
270.*
4,1,16,-.01524,.02584,
-.010521,.028094,
-.005483,.029494,
-.000278,.029998,
.004935,.029591,
.009999,.028284,
.014758,.026118,
.01524,.02584,
.02032,.03092,
.014642,.033979,
.008519,.036005,
.002138,.036938,
-.004309,.036748,
-.010625,.035441,
-.016618,.033058,
-.02032,.03092,
-.01524,.02584,
270.*
%
%ADD28MACRO28*%
%AMMACRO31*
4,1,15,.02291,.0123,
.024698,.008135,
.025735,.003723,
.025991,-.000803,
.025456,-.005304,
.024149,-.009644,
.02291,-.0123,
.02803,-.01742,
.030629,-.012288,
.032298,-.006783,
.032985,-.001071,
.03267,.004673,
.031362,.010275,
.029101,.015565,
.02803,.01742,
.02291,.0123,
180.*
4,1,15,.0123,-.02291,
.008135,-.024698,
.003723,-.025735,
-.000803,-.025991,
-.005304,-.025456,
-.009644,-.024149,
-.0123,-.02291,
-.01742,-.02803,
-.012288,-.030629,
-.006783,-.032298,
-.001071,-.032985,
.004673,-.03267,
.010275,-.031362,
.015565,-.029101,
.01742,-.02803,
.0123,-.02291,
180.*
4,1,15,-.02291,-.0123,
-.024698,-.008135,
-.025735,-.003723,
-.025991,.000803,
-.025456,.005304,
-.024149,.009644,
-.02291,.0123,
-.02803,.01742,
-.030629,.012288,
-.032298,.006783,
-.032985,.001071,
-.03267,-.004673,
-.031362,-.010275,
-.029101,-.015565,
-.02803,-.01742,
-.02291,-.0123,
180.*
4,1,15,-.0123,.02291,
-.008135,.024698,
-.003723,.025735,
.000803,.025991,
.005304,.025456,
.009644,.024149,
.0123,.02291,
.01742,.02803,
.012288,.030629,
.006783,.032298,
.001071,.032985,
-.004673,.03267,
-.010275,.031362,
-.015565,.029101,
-.01742,.02803,
-.0123,.02291,
180.*
%
%ADD31MACRO31*%
%AMMACRO22*
4,1,17,.03056,.01996,
.033562,.01435,
.035544,.008304,
.036446,.002006,
.03624,-.004353,
.034934,-.01058,
.032566,-.016486,
.03056,-.01996,
.0356,-.025,
.0394,-.018438,
.042004,-.011316,
.043331,-.003851,
.043341,.003732,
.042034,.011201,
.039451,.018331,
.035668,.024903,
.0356,.025,
.03056,.01996,
270.*
4,1,17,.01996,-.03056,
.01435,-.033562,
.008304,-.035544,
.002006,-.036446,
-.004353,-.03624,
-.01058,-.034934,
-.016486,-.032566,
-.01996,-.03056,
-.025,-.0356,
-.018438,-.0394,
-.011316,-.042004,
-.003851,-.043331,
.003732,-.043341,
.011201,-.042034,
.018331,-.039451,
.024903,-.035668,
.025,-.0356,
.01996,-.03056,
270.*
4,1,17,-.03056,-.01996,
-.033562,-.01435,
-.035544,-.008304,
-.036446,-.002006,
-.03624,.004353,
-.034934,.01058,
-.032566,.016486,
-.03056,.01996,
-.0356,.025,
-.0394,.018438,
-.042004,.011316,
-.043331,.003851,
-.043341,-.003732,
-.042034,-.011201,
-.039451,-.018331,
-.035668,-.024903,
-.0356,-.025,
-.03056,-.01996,
270.*
4,1,17,-.01996,.03056,
-.01435,.033562,
-.008304,.035544,
-.002006,.036446,
.004353,.03624,
.01058,.034934,
.016486,.032566,
.01996,.03056,
.025,.0356,
.018438,.0394,
.011316,.042004,
.003851,.043331,
-.003732,.043341,
-.011201,.042034,
-.018331,.039451,
-.024903,.035668,
-.025,.0356,
-.01996,.03056,
270.*
%
%ADD22MACRO22*%
%ADD36C,.006*%
%ADD39C,.08409*%
%ADD44C,.4043*%
%ADD43C,.41402*%
%ADD40C,.24506*%
%ADD37C,.16406*%
%ADD42C,.13266*%
%ADD41C,.35606*%
%ADD38C,.15806*%
%ADD45C,.41378*%
G75*
%LPD*%
G75*
G36*
G01X-723776Y-489221D02*
X1782976D01*
Y2987387D01*
X-723776D01*
Y-489221D01*
G37*
%LPC*%
G75*
G36*
G01X75838Y2066741D02*
G03X77828I995J1125D01*
G02X78159Y2066866I331J-375D01*
G01X92520D01*
G03X102425Y2076772I0J9905D01*
G01Y2080709D01*
G02X104331Y2082614I1906J-1D01*
G01X108657D01*
G02X108990Y2082487I0J-500D01*
G03X110992I1001J1120D01*
G02X111325Y2082614I333J-373D01*
G01X158657D01*
G02X158990Y2082487I0J-500D01*
G03X160992I1001J1120D01*
G02X161325Y2082614I333J-373D01*
G01X208657D01*
G02X208990Y2082487I0J-500D01*
G03X210992I1001J1120D01*
G02X211325Y2082614I333J-373D01*
G01X258657D01*
G02X258990Y2082487I0J-500D01*
G03X260992I1001J1120D01*
G02X261325Y2082614I333J-373D01*
G01X308657D01*
G02X308990Y2082487I0J-500D01*
G03X310992I1001J1120D01*
G02X311325Y2082614I333J-373D01*
G01X358657D01*
G02X358990Y2082487I0J-500D01*
G03X360992I1001J1120D01*
G02X361325Y2082614I333J-373D01*
G01X397638D01*
G02X401512Y2078740I0J-3874D01*
G01Y2068434D01*
G02X401387Y2068103I-500J0D01*
G03Y2066113I1125J-995D01*
G02X401512Y2065782I-375J-331D01*
G01Y2018434D01*
G02X401387Y2018103I-500J0D01*
G03Y2016113I1125J-995D01*
G02X401512Y2015782I-375J-331D01*
G01Y1968434D01*
G02X401387Y1968103I-500J0D01*
G03Y1966113I1125J-995D01*
G02X401512Y1965782I-375J-331D01*
G01Y1918434D01*
G02X401387Y1918103I-500J0D01*
G03Y1916113I1125J-995D01*
G02X401512Y1915782I-375J-331D01*
G01Y1868434D01*
G02X401387Y1868103I-500J0D01*
G03Y1866113I1125J-995D01*
G02X401512Y1865782I-375J-331D01*
G01Y1818434D01*
G02X401387Y1818103I-500J0D01*
G03Y1816113I1125J-995D01*
G02X401512Y1815782I-375J-331D01*
G01Y1768434D01*
G02X401387Y1768103I-500J0D01*
G03Y1766113I1125J-995D01*
G02X401512Y1765782I-375J-331D01*
G01Y1718434D01*
G02X401387Y1718103I-500J0D01*
G03Y1716113I1125J-995D01*
G02X401512Y1715782I-375J-331D01*
G01Y1668434D01*
G02X401387Y1668103I-500J0D01*
G03Y1666113I1125J-995D01*
G02X401512Y1665782I-375J-331D01*
G01Y1618434D01*
G02X401387Y1618103I-500J0D01*
G03Y1616113I1125J-995D01*
G02X401512Y1615782I-375J-331D01*
G01Y1568434D01*
G02X401387Y1568103I-500J0D01*
G03Y1566113I1125J-995D01*
G02X401512Y1565782I-375J-331D01*
G01Y1518434D01*
G02X401387Y1518103I-500J0D01*
G03Y1516113I1125J-995D01*
G02X401512Y1515782I-375J-331D01*
G01Y1468434D01*
G02X401387Y1468103I-500J0D01*
G03Y1466113I1125J-995D01*
G02X401512Y1465782I-375J-331D01*
G01Y1418434D01*
G02X401387Y1418103I-500J0D01*
G03Y1416113I1125J-995D01*
G02X401512Y1415782I-375J-331D01*
G01Y1368434D01*
G02X401387Y1368103I-500J0D01*
G03Y1366113I1125J-995D01*
G02X401512Y1365782I-375J-331D01*
G01Y1318434D01*
G02X401387Y1318103I-500J0D01*
G03Y1316113I1125J-995D01*
G02X401512Y1315782I-375J-331D01*
G01Y1268434D01*
G02X401387Y1268103I-500J0D01*
G03Y1266113I1125J-995D01*
G02X401512Y1265782I-375J-331D01*
G01Y1218434D01*
G02X401387Y1218103I-500J0D01*
G03Y1216113I1125J-995D01*
G02X401512Y1215782I-375J-331D01*
G01Y1168434D01*
G02X401387Y1168103I-500J0D01*
G03Y1166113I1125J-995D01*
G02X401512Y1165782I-375J-331D01*
G01Y1118434D01*
G02X401387Y1118103I-500J0D01*
G03Y1116113I1125J-995D01*
G02X401512Y1115782I-375J-331D01*
G01Y1068434D01*
G02X401387Y1068103I-500J0D01*
G03Y1066113I1125J-995D01*
G02X401512Y1065782I-375J-331D01*
G01Y1018434D01*
G02X401387Y1018103I-500J0D01*
G03Y1016113I1125J-995D01*
G02X401512Y1015782I-375J-331D01*
G01Y968434D01*
G02X401387Y968103I-500J0D01*
G03Y966113I1125J-995D01*
G02X401512Y965782I-375J-331D01*
G01Y918434D01*
G02X401387Y918103I-500J0D01*
G03Y916113I1125J-995D01*
G02X401512Y915782I-375J-331D01*
G01Y868434D01*
G02X401387Y868103I-500J0D01*
G03Y866113I1125J-995D01*
G02X401512Y865782I-375J-331D01*
G01Y818434D01*
G02X401387Y818103I-500J0D01*
G03Y816113I1125J-995D01*
G02X401512Y815782I-375J-331D01*
G01Y768434D01*
G02X401387Y768103I-500J0D01*
G03Y766113I1125J-995D01*
G02X401512Y765782I-375J-331D01*
G01Y718434D01*
G02X401387Y718103I-500J0D01*
G03Y716113I1125J-995D01*
G02X401512Y715782I-375J-331D01*
G01Y668434D01*
G02X401387Y668103I-500J0D01*
G03Y666113I1125J-995D01*
G02X401512Y665782I-375J-331D01*
G01Y618434D01*
G02X401387Y618103I-500J0D01*
G03Y616113I1125J-995D01*
G02X401512Y615782I-375J-331D01*
G01Y568434D01*
G02X401387Y568103I-500J0D01*
G03Y566113I1125J-995D01*
G02X401512Y565782I-375J-331D01*
G01Y518434D01*
G02X401387Y518103I-500J0D01*
G03Y516113I1125J-995D01*
G02X401512Y515782I-375J-331D01*
G01Y468434D01*
G02X401387Y468103I-500J0D01*
G03Y466113I1125J-995D01*
G02X401512Y465782I-375J-331D01*
G01Y418434D01*
G02X401387Y418103I-500J0D01*
G03Y416113I1125J-995D01*
G02X401512Y415782I-375J-331D01*
G01Y368434D01*
G02X401387Y368103I-500J0D01*
G03Y366113I1125J-995D01*
G02X401512Y365782I-375J-331D01*
G01Y318434D01*
G02X401387Y318103I-500J0D01*
G03Y316113I1125J-995D01*
G02X401512Y315782I-375J-331D01*
G01Y268434D01*
G02X401387Y268103I-500J0D01*
G03Y266113I1125J-995D01*
G02X401512Y265782I-375J-331D01*
G01Y218434D01*
G02X401387Y218103I-500J0D01*
G03Y216113I1125J-995D01*
G02X401512Y215782I-375J-331D01*
G01Y168434D01*
G02X401387Y168103I-500J0D01*
G03Y166113I1125J-995D01*
G02X401512Y165782I-375J-331D01*
G01Y118434D01*
G02X401387Y118103I-500J0D01*
G03Y116113I1125J-995D01*
G02X401512Y115782I-375J-331D01*
G01Y68434D01*
G02X401387Y68103I-500J0D01*
G03Y66113I1125J-995D01*
G02X401512Y65782I-375J-331D01*
G01Y18434D01*
G02X401387Y18103I-500J0D01*
G03Y16113I1125J-995D01*
G02X401512Y15782I-375J-331D01*
G01Y7874D01*
G02X397638Y4000I-3874J0D01*
G01X376547D01*
G02X376215Y4126I0J500D01*
G03X374223I-996J-1124D01*
G02X373891Y4000I-332J374D01*
G01X326547D01*
G02X326215Y4126I0J500D01*
G03X324223I-996J-1124D01*
G02X323891Y4000I-332J374D01*
G01X276547D01*
G02X276215Y4126I0J500D01*
G03X274223I-996J-1124D01*
G02X273891Y4000I-332J374D01*
G01X226547D01*
G02X226215Y4126I0J500D01*
G03X224223I-996J-1124D01*
G02X223891Y4000I-332J374D01*
G01X176547D01*
G02X176215Y4126I0J500D01*
G03X174223I-996J-1124D01*
G02X173891Y4000I-332J374D01*
G01X126547D01*
G02X126215Y4126I0J500D01*
G03X124223I-996J-1124D01*
G02X123891Y4000I-332J374D01*
G01X104331D01*
G02X102425Y5906I0J1906D01*
G01Y9843D01*
G03X92520Y19748I-9905J0D01*
G01X76549D01*
G02X76217Y19874I0J500D01*
G03X74221I-998J-1122D01*
G02X73889Y19748I-332J374D01*
G01X26549D01*
G02X26217Y19874I0J500D01*
G03X24221I-998J-1122D01*
G02X23889Y19748I-332J374D01*
G01X5906D01*
G02X4000Y21654I0J1906D01*
G01Y50707D01*
G02X4126Y51038I500J-1D01*
G03Y53030I-1125J996D01*
G02X4000Y53361I374J332D01*
G01Y98707D01*
G02X4126Y99038I500J-1D01*
G03Y101030I-1125J996D01*
G02X4000Y101361I374J332D01*
G01Y148707D01*
G02X4126Y149038I500J-1D01*
G03Y151030I-1125J996D01*
G02X4000Y151361I374J332D01*
G01Y198707D01*
G02X4126Y199038I500J-1D01*
G03Y201030I-1125J996D01*
G02X4000Y201361I374J332D01*
G01Y248707D01*
G02X4126Y249038I500J-1D01*
G03Y251030I-1125J996D01*
G02X4000Y251361I374J332D01*
G01Y298707D01*
G02X4126Y299038I500J-1D01*
G03Y301030I-1125J996D01*
G02X4000Y301361I374J332D01*
G01Y348707D01*
G02X4126Y349038I500J-1D01*
G03Y351030I-1125J996D01*
G02X4000Y351361I374J332D01*
G01Y398707D01*
G02X4126Y399038I500J-1D01*
G03Y401030I-1125J996D01*
G02X4000Y401361I374J332D01*
G01Y448707D01*
G02X4126Y449038I500J-1D01*
G03Y451030I-1125J996D01*
G02X4000Y451361I374J332D01*
G01Y498707D01*
G02X4126Y499038I500J-1D01*
G03Y501030I-1125J996D01*
G02X4000Y501361I374J332D01*
G01Y548707D01*
G02X4126Y549038I500J-1D01*
G03Y551030I-1125J996D01*
G02X4000Y551361I374J332D01*
G01Y598707D01*
G02X4126Y599038I500J-1D01*
G03Y601030I-1125J996D01*
G02X4000Y601361I374J332D01*
G01Y648707D01*
G02X4126Y649038I500J-1D01*
G03Y651030I-1125J996D01*
G02X4000Y651361I374J332D01*
G01Y698707D01*
G02X4126Y699038I500J-1D01*
G03Y701030I-1125J996D01*
G02X4000Y701361I374J332D01*
G01Y748707D01*
G02X4126Y749038I500J-1D01*
G03Y751030I-1125J996D01*
G02X4000Y751361I374J332D01*
G01Y798707D01*
G02X4126Y799038I500J-1D01*
G03Y801030I-1125J996D01*
G02X4000Y801361I374J332D01*
G01Y848707D01*
G02X4126Y849038I500J-1D01*
G03Y851030I-1125J996D01*
G02X4000Y851361I374J332D01*
G01Y898707D01*
G02X4126Y899038I500J-1D01*
G03Y901030I-1125J996D01*
G02X4000Y901361I374J332D01*
G01Y948707D01*
G02X4126Y949038I500J-1D01*
G03Y951030I-1125J996D01*
G02X4000Y951361I374J332D01*
G01Y998707D01*
G02X4126Y999038I500J-1D01*
G03Y1001030I-1125J996D01*
G02X4000Y1001361I374J332D01*
G01Y1048707D01*
G02X4126Y1049038I500J-1D01*
G03Y1051030I-1125J996D01*
G02X4000Y1051361I374J332D01*
G01Y1098707D01*
G02X4126Y1099038I500J-1D01*
G03Y1101030I-1125J996D01*
G02X4000Y1101361I374J332D01*
G01Y1148707D01*
G02X4126Y1149038I500J-1D01*
G03Y1151030I-1125J996D01*
G02X4000Y1151361I374J332D01*
G01Y1198707D01*
G02X4126Y1199038I500J-1D01*
G03Y1201030I-1125J996D01*
G02X4000Y1201361I374J332D01*
G01Y1248707D01*
G02X4126Y1249038I500J-1D01*
G03Y1251030I-1125J996D01*
G02X4000Y1251361I374J332D01*
G01Y1298707D01*
G02X4126Y1299038I500J-1D01*
G03Y1301030I-1125J996D01*
G02X4000Y1301361I374J332D01*
G01Y1348707D01*
G02X4126Y1349038I500J-1D01*
G03Y1351030I-1125J996D01*
G02X4000Y1351361I374J332D01*
G01Y1398707D01*
G02X4126Y1399038I500J-1D01*
G03Y1401030I-1125J996D01*
G02X4000Y1401361I374J332D01*
G01Y1448707D01*
G02X4126Y1449038I500J-1D01*
G03Y1451030I-1125J996D01*
G02X4000Y1451361I374J332D01*
G01Y1498707D01*
G02X4126Y1499038I500J-1D01*
G03Y1501030I-1125J996D01*
G02X4000Y1501361I374J332D01*
G01Y1548707D01*
G02X4126Y1549038I500J-1D01*
G03Y1551030I-1125J996D01*
G02X4000Y1551361I374J332D01*
G01Y1593269D01*
G02X4127Y1593602I500J0D01*
G03Y1595602I-1121J1000D01*
G02X4000Y1595935I373J333D01*
G01Y1608826D01*
G02X4128Y1609160I500J0D01*
G03Y1611170I-1116J1005D01*
G02X4000Y1611504I372J334D01*
G01Y1648707D01*
G02X4126Y1649038I500J-1D01*
G03Y1651030I-1125J996D01*
G02X4000Y1651361I374J332D01*
G01Y1698707D01*
G02X4126Y1699038I500J-1D01*
G03Y1701030I-1125J996D01*
G02X4000Y1701361I374J332D01*
G01Y1748707D01*
G02X4126Y1749038I500J-1D01*
G03Y1751030I-1125J996D01*
G02X4000Y1751361I374J332D01*
G01Y1798707D01*
G02X4126Y1799038I500J-1D01*
G03Y1801030I-1125J996D01*
G02X4000Y1801361I374J332D01*
G01Y1848707D01*
G02X4126Y1849038I500J-1D01*
G03Y1851030I-1125J996D01*
G02X4000Y1851361I374J332D01*
G01Y1898707D01*
G02X4126Y1899038I500J-1D01*
G03Y1901030I-1125J996D01*
G02X4000Y1901361I374J332D01*
G01Y1948707D01*
G02X4126Y1949038I500J-1D01*
G03Y1951030I-1125J996D01*
G02X4000Y1951361I374J332D01*
G01Y1998707D01*
G02X4126Y1999038I500J-1D01*
G03Y2001030I-1125J996D01*
G02X4000Y2001361I374J332D01*
G01Y2048707D01*
G02X4126Y2049038I500J-1D01*
G03Y2051030I-1125J996D01*
G02X4000Y2051361I374J332D01*
G01Y2064961D01*
G02X5905Y2066866I1905J0D01*
G01X25507D01*
G02X25838Y2066741I0J-500D01*
G03X27828I995J1125D01*
G02X28159Y2066866I331J-375D01*
G01X75507D01*
G02X75838Y2066741I0J-500D01*
G37*
%LPD*%
G75*
G36*
G01X17980Y1347510D02*
Y1348455D01*
X17981D01*
G02X22973Y1348450I2490J-5857D01*
G01X22974D01*
Y1347505D01*
G03X23213Y1347078I500J0D01*
G02X23859Y1346612I-2741J-4480D01*
G01X25411D01*
X25412Y1346611D01*
G02X14107Y1342598I-4940J-4013D01*
G02X15507Y1346580I6365J-1D01*
G01X17048D01*
G02X17740Y1347083I3424J-3982D01*
G03X17980Y1347510I-260J427D01*
G37*
G36*
G01X17976Y989245D02*
Y990190D01*
X17977D01*
G02X22969Y990185I2490J-5857D01*
G01X22970D01*
Y989240D01*
G03X23209Y988813I500J0D01*
G02X23856Y988346I-2741J-4480D01*
G01X25408D01*
G02X14103Y984333I-4940J-4013D01*
G02X15503Y988316I6365J0D01*
G01X17045D01*
G02X17736Y988818I3422J-3984D01*
G03X17976Y989245I-260J427D01*
G37*
G36*
G01X170004Y727205D02*
G02X156767Y727182I-6619J0D01*
G02X169983Y727726I6618J30D01*
G02X169986Y727689I-6594J-553D01*
G02X170004Y727205I-6600J-488D01*
G37*
G36*
G01Y552205D02*
G02X156767Y552182I-6619J0D01*
G02X169983Y552726I6618J30D01*
G02X169986Y552689I-6594J-553D01*
G02X170004Y552205I-6600J-488D01*
G37*
G36*
G01X292850Y1881102D02*
Y1885039D01*
G02X321322I14236J0D01*
G01Y1881102D01*
G02X292850I-14236J0D01*
G37*
G36*
G01X169982Y1952727D02*
G02X170003Y1952205I-6597J-527D01*
G02X156766I-6618J0D01*
G02X169982Y1952727I6618J0D01*
G37*
G36*
G01X86042Y1864960D02*
G02X74584Y1846445I-20687J-1D01*
G02X75698Y1882876I-9230J18515D01*
G02X86042Y1864960I-10343J-17916D01*
G37*
G36*
G01X169982Y1777727D02*
G02X170003Y1777205I-6597J-527D01*
G02X156766I-6618J0D01*
G02X169982Y1777727I6618J0D01*
G37*
G36*
G01Y1602727D02*
G02X170003Y1602205I-6597J-527D01*
G02X156766I-6618J0D01*
G02X169982Y1602727I6618J0D01*
G37*
G36*
G01Y1427727D02*
G02X170003Y1427205I-6597J-527D01*
G02X156766I-6618J0D01*
G02X169982Y1427727I6618J0D01*
G37*
G36*
G01Y1252727D02*
G02X170003Y1252205I-6597J-527D01*
G02X156766I-6618J0D01*
G02X169982Y1252727I6618J0D01*
G37*
G36*
G01Y1077727D02*
G02X170003Y1077205I-6597J-527D01*
G02X156766I-6618J0D01*
G02X169982Y1077727I6618J0D01*
G37*
G36*
G01X26828Y1054605D02*
G02X20471Y1060962I-6357J0D01*
G01Y1060963D01*
X20472D01*
G02X26828Y1054605I-1J-6357D01*
G37*
G36*
G01X169982Y902727D02*
G02X170003Y902205I-6597J-527D01*
G02X156766I-6618J0D01*
G02X169982Y902727I6618J0D01*
G37*
G36*
G01Y377727D02*
G02X170002Y377205I-6597J-514D01*
G02X156766I-6618J0D01*
G02X169982Y377727I6618J0D01*
G37*
G36*
G01Y202727D02*
G02X170002Y202205I-6597J-514D01*
G02X156766I-6618J0D01*
G02X169982Y202727I6618J0D01*
G37*
G36*
G01Y27727D02*
G02X170002Y27205I-6597J-514D01*
G02X156766I-6618J0D01*
G02X169982Y27727I6618J0D01*
G37*
G54D39*
X30473Y102007D03*
Y137440D03*
X30197Y305027D03*
Y352271D03*
X30473Y1855008D03*
Y1890441D03*
Y1937007D03*
Y1972440D03*
Y2012007D03*
Y2047440D03*
G54D44*
X307086Y127164D03*
X307088Y477164D03*
X307087Y827164D03*
Y1343503D03*
Y1693503D03*
Y2043503D03*
G54D43*
X65354Y114960D03*
G54D40*
X307086Y308267D03*
G54D37*
X29979Y30500D03*
Y75500D03*
Y166500D03*
Y211500D03*
Y239500D03*
Y284500D03*
Y375500D03*
Y420500D03*
G54D42*
X373385Y32520D03*
Y207520D03*
Y382520D03*
X373386Y557520D03*
Y732520D03*
X373385Y907520D03*
Y1082520D03*
Y1257520D03*
Y1432520D03*
Y1607520D03*
Y1782520D03*
Y1957520D03*
G54D41*
X359842Y78780D03*
Y253780D03*
Y428779D03*
Y603779D03*
Y778780D03*
Y953780D03*
Y1128779D03*
Y1303780D03*
Y1478780D03*
Y1653780D03*
Y1828779D03*
Y2003780D03*
G54D38*
X30254Y514500D03*
Y559500D03*
Y1572504D03*
Y1617504D03*
G54D45*
X65354Y464960D03*
Y814960D03*
Y1164960D03*
Y1514960D03*
G54D11*
X25219Y18752D03*
X3001Y52034D03*
Y100034D03*
Y150034D03*
Y200034D03*
Y250034D03*
Y300034D03*
Y350034D03*
Y400034D03*
Y450034D03*
Y500034D03*
X13441Y495961D03*
X3001Y550034D03*
X10914Y578848D03*
X15984Y578849D03*
X3001Y600034D03*
Y650034D03*
Y700034D03*
Y750034D03*
Y800034D03*
Y850034D03*
Y900034D03*
Y950034D03*
Y1000034D03*
Y1050034D03*
Y1100034D03*
Y1150034D03*
Y1200034D03*
Y1250034D03*
Y1300034D03*
Y1350034D03*
Y1400034D03*
Y1450034D03*
Y1500034D03*
Y1550034D03*
X11541Y1562330D03*
X3006Y1594602D03*
X3012Y1610165D03*
X3001Y1650034D03*
X11153Y1638435D03*
X16552Y1638005D03*
X3001Y1700034D03*
Y1750034D03*
Y1800034D03*
Y1850034D03*
Y1900034D03*
Y1950034D03*
Y2000034D03*
Y2050034D03*
X48433Y866179D03*
X48467Y869278D03*
X49441Y1238962D03*
X45581Y1278420D03*
X45413Y1283724D03*
X45244Y1289067D03*
X45350Y1299697D03*
X45267Y1294203D03*
X45281Y1310893D03*
X45244Y1305787D03*
X46980Y1335843D03*
Y1325843D03*
Y1315843D03*
Y1320843D03*
Y1330843D03*
Y1345843D03*
Y1340843D03*
X26833Y2067866D03*
X61888Y666012D03*
X57124Y675327D03*
X54483Y679810D03*
X59236Y670758D03*
X70865Y872278D03*
Y866278D03*
Y860278D03*
Y897750D03*
Y890116D03*
X60815Y1019026D03*
X63577Y1019115D03*
X57458Y1253378D03*
X54543Y1296513D03*
X63061Y1296312D03*
X67568Y1296654D03*
X61866Y1309190D03*
X54543Y1308995D03*
X67568Y1307829D03*
X54130Y1313763D03*
X70340Y1328203D03*
X61866Y1342104D03*
X55544Y1770835D03*
X55080Y1762982D03*
X54948Y1755171D03*
X56425Y1778371D03*
X70376Y1796383D03*
X75219Y18752D03*
X97417Y32853D03*
Y37438D03*
X97536Y376580D03*
X97457Y371909D03*
X97985Y391220D03*
X97643Y396024D03*
X93223Y417736D03*
X94347Y421562D03*
X86187Y680710D03*
X79520Y682439D03*
X88681Y704108D03*
X81563Y705437D03*
X86673Y685710D03*
X79536D03*
X96308Y696622D03*
X98591Y720745D03*
X98564Y715937D03*
X97443Y739962D03*
X97534Y735248D03*
X98124Y745139D03*
X95775Y751469D03*
X89338Y878294D03*
X91733Y899382D03*
X92633Y907404D03*
X91294Y926951D03*
X98139Y990959D03*
X76446Y1014871D03*
X79499D03*
X96904Y1067515D03*
X82763Y1060051D03*
X96948Y1092036D03*
X96949Y1087095D03*
X96774Y1072226D03*
X96684Y1081791D03*
X96510Y1395382D03*
X97403Y1424340D03*
X97825Y1419492D03*
X96993Y1443743D03*
X96996Y1438980D03*
X97465Y1447919D03*
X95236Y1453321D03*
X88837Y1771103D03*
X91460Y1765062D03*
X93771Y1748227D03*
X80376Y1772098D03*
Y1768566D03*
X75376Y1796236D03*
X80376Y1796163D03*
X85376Y1796236D03*
X80376Y1775609D03*
X76833Y2067866D03*
X106335Y22580D03*
X106958Y26285D03*
X108082Y38899D03*
X102646Y49461D03*
X101430Y41803D03*
X107405Y49898D03*
X107037Y34687D03*
X104350Y62293D03*
X107263Y72244D03*
X109054Y58250D03*
X104116Y82557D03*
X108672Y86150D03*
X106836Y376461D03*
X106709Y391219D03*
X105451Y406795D03*
X114498Y396207D03*
X101990Y426104D03*
X109475Y434743D03*
X111017Y419566D03*
X102960Y672823D03*
X113018Y706356D03*
X107025Y725368D03*
X105087Y754126D03*
X106935Y745139D03*
X107173Y735219D03*
X101244Y774100D03*
X112836Y769122D03*
X111967Y795261D03*
X115139Y849240D03*
X105395Y972040D03*
X102611Y972220D03*
X100687Y999391D03*
X107351Y1093484D03*
X107235Y1081791D03*
X107215Y1072208D03*
X98652Y1096403D03*
X108779Y1105760D03*
X105152Y1118381D03*
X112503Y1115860D03*
X105684Y1125919D03*
X108468Y1129286D03*
X100719Y1312810D03*
Y1306810D03*
Y1330810D03*
Y1336810D03*
Y1324810D03*
Y1318810D03*
Y1346065D03*
X106962Y1434041D03*
X106921Y1419492D03*
X106763Y1444599D03*
X107006Y1452651D03*
X105455Y1472894D03*
X108574Y1463389D03*
X113518Y1489571D03*
X99103Y1765722D03*
X99068Y1760827D03*
X107355Y1770437D03*
X99047Y1785571D03*
X98873Y1780542D03*
X99294Y1789947D03*
X107391Y1794460D03*
X107220Y1791589D03*
X107373Y1780544D03*
X105669Y1815227D03*
X108819Y1812118D03*
X106819Y1802230D03*
X108819Y1824470D03*
X109991Y2083607D03*
X125219Y3002D03*
X144878Y1738861D03*
X162384Y56744D03*
X157558Y51426D03*
X161742Y72497D03*
X162586Y68130D03*
X159417Y91281D03*
X158901Y85017D03*
X169500Y126110D03*
Y118626D03*
Y111407D03*
X166500D03*
Y118626D03*
Y126110D03*
X169329Y140623D03*
X169500Y132705D03*
X169329Y148066D03*
X166329D03*
X166500Y132705D03*
X166329Y140623D03*
X169329Y156102D03*
Y163621D03*
X166329D03*
Y156102D03*
X161377Y407575D03*
X156865Y401207D03*
X161257Y420869D03*
X159019Y439268D03*
X158807Y432969D03*
X159430Y461714D03*
X156430D03*
X159430Y483012D03*
X159259Y490930D03*
X159430Y468933D03*
Y476417D03*
X156430D03*
Y468933D03*
X156259Y490930D03*
X156430Y483012D03*
X159259Y513928D03*
Y498373D03*
Y506409D03*
X156259D03*
Y498373D03*
Y513928D03*
X156610Y751063D03*
X161826Y756757D03*
X161131Y774878D03*
X161644Y764231D03*
X158956Y780982D03*
X159053Y787280D03*
X158444Y822725D03*
X165872D03*
X162872D03*
X155444D03*
X165872Y830209D03*
X158444D03*
X165872Y836804D03*
X158444D03*
X165701Y844722D03*
X158273D03*
X165701Y852165D03*
X158273D03*
X155273D03*
X162701D03*
X155273Y844722D03*
X162701D03*
X155444Y836804D03*
X162872D03*
X155444Y830209D03*
X162872D03*
X165701Y860201D03*
X158273D03*
X165701Y867720D03*
X158273D03*
X155273D03*
X162701D03*
X155273Y860201D03*
X162701D03*
X164539Y1116135D03*
X162140Y1106853D03*
X156854Y1101031D03*
X159382Y1136151D03*
X158456Y1129045D03*
X156124Y1176256D03*
X163552D03*
Y1183740D03*
Y1190335D03*
X156124D03*
Y1183740D03*
X163552Y1169037D03*
X156124D03*
X153124D03*
X160552D03*
X153124Y1183740D03*
Y1190335D03*
X160552D03*
Y1183740D03*
Y1176256D03*
X153124D03*
X169375Y1183740D03*
Y1190335D03*
Y1176256D03*
X163381Y1198253D03*
X155953D03*
X152953D03*
X160381D03*
X169204D03*
X158618Y1399448D03*
X164037Y1400226D03*
X170351Y1401324D03*
X159192Y1451105D03*
X163099Y1457084D03*
X162524Y1462651D03*
X162242Y1471380D03*
X159216Y1477124D03*
X154109Y1499221D03*
X161537D03*
Y1506440D03*
X170360D03*
X154109D03*
X157109D03*
X164537D03*
Y1499221D03*
X157109D03*
X159526Y1483434D03*
X153938Y1528437D03*
X154109Y1513924D03*
Y1520519D03*
X170360Y1513924D03*
Y1520519D03*
X161537D03*
Y1513924D03*
X161366Y1528437D03*
X170189D03*
X164366D03*
X164537Y1513924D03*
Y1520519D03*
X157109D03*
Y1513924D03*
X156938Y1528437D03*
X153938Y1535880D03*
Y1543916D03*
Y1551435D03*
X170189Y1535880D03*
Y1543916D03*
X161366Y1535880D03*
Y1543916D03*
Y1551435D03*
X170189D03*
X164366D03*
Y1543916D03*
Y1535880D03*
X156938Y1551435D03*
Y1543916D03*
Y1535880D03*
X163257Y1737619D03*
X150309Y1737009D03*
X168151Y1739208D03*
X165782Y1732903D03*
X156183Y1735240D03*
X163250Y1815631D03*
X162140Y1807740D03*
X156452Y1800821D03*
X159822Y1831380D03*
X159075Y1825087D03*
X155091Y1866003D03*
X162519D03*
X159519D03*
X152091D03*
X155091Y1880706D03*
Y1887301D03*
X162519D03*
Y1880706D03*
Y1873222D03*
X155091D03*
X152091D03*
X168342D03*
X159519D03*
Y1880706D03*
Y1887301D03*
X168342D03*
Y1880706D03*
X152091Y1887301D03*
Y1880706D03*
X154920Y1902662D03*
Y1910698D03*
X162348Y1902662D03*
Y1910698D03*
X154920Y1895219D03*
X162348D03*
X168171D03*
X159348D03*
X151920D03*
X159348Y1910698D03*
Y1902662D03*
X168171Y1910698D03*
Y1902662D03*
X151920Y1910698D03*
Y1902662D03*
X154920Y1918217D03*
X162348D03*
X168171D03*
X159348D03*
X151920D03*
X159991Y2083607D03*
X175219Y3002D03*
X176928Y126110D03*
Y118626D03*
Y111407D03*
X173928D03*
Y118626D03*
Y126110D03*
X176757Y140623D03*
X176928Y132705D03*
X176757Y148066D03*
X173757D03*
X173928Y132705D03*
X173757Y140623D03*
X176757Y156102D03*
Y163621D03*
X173757D03*
Y156102D03*
X175033Y261594D03*
Y268813D03*
X178033D03*
Y261594D03*
X175033Y282892D03*
X174862Y290810D03*
Y298253D03*
X175033Y276297D03*
X178033D03*
X177862Y298253D03*
Y290810D03*
X178033Y282892D03*
X174862Y313808D03*
Y306289D03*
X177862D03*
Y313808D03*
X182191Y822725D03*
X174695D03*
X171695D03*
X179191D03*
X174524Y844722D03*
Y852165D03*
X182191Y830209D03*
X174695D03*
X182191Y836804D03*
X174695D03*
X182020Y844722D03*
Y852165D03*
X179020D03*
Y844722D03*
X171695Y836804D03*
X179191D03*
X171695Y830209D03*
X179191D03*
X171524Y852165D03*
Y844722D03*
X174524Y860201D03*
Y867720D03*
X182020Y860201D03*
Y867720D03*
X179020D03*
Y860201D03*
X171524Y867720D03*
Y860201D03*
X184284Y948331D03*
X175989Y944537D03*
X176011Y936829D03*
X184196Y967371D03*
X175359Y963486D03*
X175561Y955964D03*
X175135Y972490D03*
X184632Y983423D03*
X175022Y980281D03*
X175742Y989958D03*
X175449Y997660D03*
X184353Y1001556D03*
X184118Y1019280D03*
X188385Y1020810D03*
X175698Y1008730D03*
X175473Y1016296D03*
X175448Y1031766D03*
X175897Y1023997D03*
X179871Y1176256D03*
Y1190335D03*
Y1183740D03*
X172375Y1176256D03*
Y1190335D03*
Y1183740D03*
X176871D03*
Y1190335D03*
Y1176256D03*
X179700Y1198253D03*
X172204D03*
X176700D03*
X176083Y1402321D03*
X177856Y1506440D03*
X173360D03*
X180856D03*
X177856Y1513924D03*
Y1520519D03*
X177685Y1528437D03*
X173189D03*
X173360Y1520519D03*
Y1513924D03*
X180685Y1528437D03*
X180856Y1520519D03*
Y1513924D03*
X177685Y1535880D03*
Y1543916D03*
Y1551435D03*
X173189D03*
Y1543916D03*
Y1535880D03*
X180685Y1551435D03*
Y1543916D03*
Y1535880D03*
X173394Y1736051D03*
X178838Y1880706D03*
Y1887301D03*
Y1873222D03*
X171342Y1880706D03*
Y1887301D03*
Y1873222D03*
X175838D03*
Y1887301D03*
Y1880706D03*
X178667Y1902662D03*
Y1910698D03*
Y1895219D03*
X171171Y1902662D03*
Y1910698D03*
Y1895219D03*
X175667D03*
Y1910698D03*
Y1902662D03*
X178667Y1918217D03*
X171171D03*
X175667D03*
X219131Y1663167D03*
Y1670386D03*
Y1684465D03*
Y1677870D03*
X218960Y1692383D03*
Y1699826D03*
Y1707862D03*
Y1715381D03*
X209991Y2083607D03*
X225219Y3002D03*
X237955Y56999D03*
X240955D03*
X237955Y64483D03*
X237784Y78996D03*
X237955Y71078D03*
X240955D03*
X240784Y78996D03*
X240955Y64483D03*
X237784Y94475D03*
Y101994D03*
Y86439D03*
X240784D03*
Y101994D03*
Y94475D03*
X241033Y244995D03*
X233537D03*
X224714Y237776D03*
Y244995D03*
X227714D03*
Y237776D03*
X236537Y244995D03*
X241033Y259074D03*
X240862Y266992D03*
Y274435D03*
X241033Y252479D03*
X233537Y259074D03*
X233366Y266992D03*
Y274435D03*
X224714Y259074D03*
X224543Y266992D03*
Y274435D03*
X233537Y252479D03*
X224714D03*
X227714D03*
X236537D03*
X227543Y274435D03*
Y266992D03*
X227714Y259074D03*
X236366Y274435D03*
Y266992D03*
X236537Y259074D03*
X240862Y289990D03*
Y282471D03*
X233366Y289990D03*
X224543D03*
X233366Y282471D03*
X224543D03*
X227543D03*
X236366D03*
X227543Y289990D03*
X236366D03*
X229548Y461083D03*
X232548D03*
X238371Y482381D03*
X238200Y490299D03*
X229548Y482381D03*
X229377Y490299D03*
X238371Y468302D03*
Y475786D03*
X229548Y468302D03*
Y475786D03*
X232548D03*
Y468302D03*
X241371Y475786D03*
Y468302D03*
X232377Y490299D03*
X232548Y482381D03*
X241200Y490299D03*
X241371Y482381D03*
X238200Y513297D03*
X229377D03*
X238200Y497742D03*
X229377D03*
X238200Y505778D03*
X229377D03*
X232377D03*
X241200D03*
X232377Y497742D03*
X241200D03*
X232377Y513297D03*
X241200D03*
X227963Y608108D03*
X235391D03*
X227963Y601513D03*
X235391D03*
Y594029D03*
X227963D03*
X230963D03*
X238391D03*
Y601513D03*
X230963D03*
X238391Y608108D03*
X230963D03*
X227792Y631505D03*
X235220D03*
X227792Y623469D03*
X235220D03*
X227792Y616026D03*
X235220D03*
X238220D03*
X230792D03*
X238220Y623469D03*
X230792D03*
X238220Y631505D03*
X230792D03*
X227792Y639024D03*
X235220D03*
X238220D03*
X230792D03*
X231339Y959673D03*
X238767D03*
Y967157D03*
Y973752D03*
X231339D03*
Y967157D03*
X238767Y952454D03*
X231339D03*
X234339D03*
X241767D03*
X234339Y967157D03*
Y973752D03*
X241767D03*
Y967157D03*
Y959673D03*
X234339D03*
X238596Y981670D03*
X231168D03*
X238596Y997149D03*
Y989113D03*
X231168Y997149D03*
Y989113D03*
X234168D03*
Y997149D03*
X241596Y989113D03*
Y997149D03*
X234168Y981670D03*
X241596D03*
X238596Y1004668D03*
X231168D03*
X234168D03*
X241596D03*
X235659Y1215296D03*
X228231D03*
X235659Y1207777D03*
Y1199741D03*
X228231Y1207777D03*
Y1199741D03*
X231231D03*
Y1207777D03*
X238659Y1199741D03*
Y1207777D03*
X231231Y1215296D03*
X238659D03*
X235382Y1670386D03*
X226559Y1663167D03*
Y1670386D03*
X222131D03*
X229559D03*
Y1663167D03*
X238382Y1670386D03*
X222131Y1663167D03*
X242878Y1670386D03*
X235382Y1677870D03*
X235211Y1692383D03*
X235382Y1684465D03*
X226559D03*
Y1677870D03*
X226388Y1692383D03*
X221960D03*
X222131Y1677870D03*
Y1684465D03*
X229388Y1692383D03*
X229559Y1677870D03*
Y1684465D03*
X238382D03*
X238211Y1692383D03*
X238382Y1677870D03*
X242878D03*
Y1684465D03*
X242707Y1692383D03*
X235211Y1699826D03*
X226388D03*
X235211Y1715381D03*
Y1707862D03*
X226388D03*
Y1715381D03*
X221960D03*
Y1707862D03*
X229388Y1715381D03*
Y1707862D03*
X238211D03*
Y1715381D03*
X221960Y1699826D03*
X229388D03*
X238211D03*
X242707D03*
Y1707862D03*
Y1715381D03*
X245451Y56999D03*
X248451D03*
X245451Y64483D03*
X245280Y78996D03*
X245451Y71078D03*
X248451D03*
X248280Y78996D03*
X248451Y64483D03*
X245280Y94475D03*
Y101994D03*
Y86439D03*
X248280D03*
Y101994D03*
Y94475D03*
X267627Y115559D03*
X256947Y128276D03*
X257125Y115559D03*
X267420Y147540D03*
X263086Y147675D03*
X244033Y244995D03*
Y252479D03*
X243862Y274435D03*
Y266992D03*
X244033Y259074D03*
X243862Y282471D03*
Y289990D03*
X265722Y463102D03*
X245867Y482381D03*
X245696Y490299D03*
X245867Y468302D03*
Y475786D03*
X248867D03*
Y468302D03*
X248696Y490299D03*
X248867Y482381D03*
X265737Y473680D03*
X245696Y513297D03*
Y497742D03*
Y505778D03*
X248696D03*
Y497742D03*
Y513297D03*
X264516Y497341D03*
X251710Y608108D03*
Y601513D03*
Y594029D03*
X244214Y608108D03*
Y601513D03*
Y594029D03*
X247214D03*
Y601513D03*
Y608108D03*
X254710Y594029D03*
Y601513D03*
Y608108D03*
X264433Y624321D03*
X267433D03*
X251539Y631505D03*
Y623469D03*
Y616026D03*
X244043Y631505D03*
Y623469D03*
Y616026D03*
X247043D03*
Y623469D03*
Y631505D03*
X254539Y616026D03*
Y623469D03*
Y631505D03*
X251539Y639024D03*
X244043D03*
X247043D03*
X254539D03*
X255837Y823626D03*
X255687Y812192D03*
X264181Y847354D03*
X255086Y959673D03*
Y973752D03*
Y967157D03*
X247590Y959673D03*
Y973752D03*
Y967157D03*
X250590D03*
Y973752D03*
Y959673D03*
X258086Y967157D03*
Y973752D03*
Y959673D03*
X254915Y981670D03*
Y997149D03*
Y989113D03*
X247419Y981670D03*
Y997149D03*
Y989113D03*
X250419D03*
Y997149D03*
Y981670D03*
X257915Y989113D03*
Y997149D03*
Y981670D03*
X254915Y1004668D03*
X247419D03*
X250419D03*
X257915D03*
X267194Y1191777D03*
X262559D03*
X251978Y1215296D03*
X244482D03*
X251978Y1207777D03*
Y1199741D03*
X244482Y1207777D03*
Y1199741D03*
X247482D03*
Y1207777D03*
X254978Y1199741D03*
Y1207777D03*
X247482Y1215296D03*
X254978D03*
X245878Y1670386D03*
X245707Y1692383D03*
X245878Y1684465D03*
Y1677870D03*
X245707Y1715381D03*
Y1707862D03*
Y1699826D03*
X259991Y2083607D03*
X275219Y3002D03*
X276523Y147585D03*
X271943Y147630D03*
X271547Y260353D03*
X276617Y256400D03*
X281193Y256624D03*
X285513Y322688D03*
X281074D03*
X289895D03*
X281569Y436169D03*
X286665Y432844D03*
X291002D03*
X274991Y463099D03*
X277776Y497341D03*
X273405D03*
X268938D03*
X285348Y610540D03*
X290984Y607215D03*
X276044Y624627D03*
X279044D03*
X274514Y672192D03*
X270109D03*
X283340D03*
X278955D03*
X273114Y785968D03*
X278184Y782643D03*
X282737D03*
X270070Y812192D03*
X268686Y847488D03*
X277788Y847237D03*
X273305D03*
X285966Y959767D03*
X291194Y956442D03*
X285666Y1016162D03*
X281124D03*
X290107D03*
X282958Y1134471D03*
X288188Y1131146D03*
X276807Y1191777D03*
X272082D03*
X283808Y1308959D03*
X289210Y1305634D03*
X284240Y1374544D03*
X279518Y1374543D03*
X275052Y1374715D03*
X270579Y1374626D03*
X275521Y1479435D03*
X279990D03*
X270234Y1482760D03*
X291054Y1543211D03*
X284086Y1659883D03*
X289421Y1656558D03*
X279703Y1723398D03*
X284583Y1723465D03*
X289499Y1723735D03*
X274704Y1723196D03*
X281066Y1834569D03*
X291550Y1829846D03*
X286623Y1829400D03*
X280240Y1858668D03*
X279976Y1864565D03*
X287121Y1898327D03*
X282717D03*
X278262D03*
X273817D03*
X299687Y78778D03*
X304151D03*
X308651D03*
X313089D03*
X294483Y82732D03*
X308057Y248863D03*
X306267Y241010D03*
X314914Y238162D03*
X314940Y252083D03*
X294506Y322688D03*
X295509Y607215D03*
X295874Y956442D03*
X294617Y1016162D03*
X309678Y1053262D03*
X292698Y1131146D03*
X312527Y1162266D03*
X312698Y1172804D03*
X294133Y1305634D03*
X314183Y1403423D03*
X313894Y1513883D03*
X302267Y1524401D03*
X301734Y1513883D03*
X304870Y1543211D03*
X300392D03*
X295675D03*
X312077Y1575871D03*
X294090Y1656558D03*
X293606Y1858668D03*
X314562Y2009087D03*
X309991Y2083607D03*
X325219Y3002D03*
X331403Y51409D03*
X333889Y56021D03*
X338227Y61559D03*
X322005Y78778D03*
X317567D03*
X320372Y225979D03*
X318088Y231820D03*
X321899Y238137D03*
X331046Y232021D03*
X320961Y250105D03*
X324709Y231580D03*
X335522Y404033D03*
X323313Y418313D03*
X326196Y413982D03*
X328950Y409216D03*
X320980Y423225D03*
X336617Y577978D03*
X319305Y582111D03*
X329636Y584715D03*
X317724Y588250D03*
X337387Y586230D03*
X320380Y576491D03*
X331867Y589810D03*
X333750Y595326D03*
X321742Y599041D03*
X331568Y752967D03*
X339012Y752859D03*
X329336Y762693D03*
X334010Y758588D03*
X327524Y758020D03*
X329938Y948756D03*
X332527Y943746D03*
X324098Y946104D03*
X318557Y941178D03*
X323868Y929978D03*
X326646Y939788D03*
X336160Y937262D03*
X328583Y933262D03*
X321425Y951577D03*
X324246Y1051786D03*
X335677Y1048904D03*
X317592Y1053050D03*
X337509Y1109598D03*
X328989Y1121090D03*
X326558Y1126368D03*
X325796Y1162266D03*
X327452Y1279447D03*
X321978Y1282086D03*
X329619Y1284016D03*
X327932Y1289221D03*
X325636Y1399114D03*
X334646Y1400804D03*
X323720Y1570924D03*
X333474Y1566686D03*
X335963Y1573797D03*
X323813Y1753231D03*
X329887Y1752081D03*
X332399Y1926787D03*
X324803Y2005272D03*
X320045Y2005215D03*
X359931Y52189D03*
X348289Y50863D03*
X345089Y56190D03*
X340373Y51579D03*
X361799Y311938D03*
X362236Y324983D03*
X342097Y401684D03*
X363825Y401768D03*
X342900Y580126D03*
X354000Y652170D03*
X356559Y675167D03*
X362577Y752783D03*
X344109Y751809D03*
X343656Y933725D03*
X345578Y1047844D03*
X344099Y1106798D03*
X363169Y1329686D03*
X351391D03*
X354391D03*
X363169Y1350706D03*
Y1360043D03*
Y1340201D03*
X351391Y1350706D03*
Y1360043D03*
Y1340201D03*
X354391D03*
Y1360043D03*
Y1350706D03*
X363169Y1376210D03*
Y1367771D03*
X351391Y1376210D03*
Y1367771D03*
X354391D03*
Y1376210D03*
X344130Y1401670D03*
X350690Y1403243D03*
X348710Y1570187D03*
X361011Y1568890D03*
X343402Y1572080D03*
X348245Y1575241D03*
X355364Y1570990D03*
X352337Y1887285D03*
X345537Y1916558D03*
X344402Y1911123D03*
X363361Y1918313D03*
X358318Y1920680D03*
X363411Y1923459D03*
X340336Y1922409D03*
X359991Y2083607D03*
X375219Y3002D03*
X372204Y56126D03*
X379257Y52158D03*
X387524Y76847D03*
X374442Y406857D03*
X374542Y401282D03*
X368907Y404308D03*
X376654Y754748D03*
X382892Y767710D03*
X386790Y774338D03*
X379335Y1189778D03*
X383276Y1184136D03*
X386816Y1179841D03*
X376472Y1194999D03*
X373674Y1199967D03*
X371523Y1204725D03*
X366169Y1329686D03*
Y1340201D03*
Y1360043D03*
Y1350706D03*
X373564Y1352548D03*
X366169Y1367771D03*
Y1376210D03*
X374681Y1365620D03*
X367829Y1566108D03*
X366306Y1899864D03*
X374431Y1901397D03*
X374775Y1919243D03*
X379403Y1917261D03*
X369748Y1921795D03*
X402512Y17108D03*
Y67108D03*
Y117108D03*
Y167108D03*
Y217108D03*
Y267108D03*
Y317108D03*
Y367108D03*
Y417108D03*
Y467108D03*
Y517108D03*
Y567108D03*
Y617108D03*
Y667108D03*
Y717108D03*
Y767108D03*
Y817108D03*
Y867108D03*
Y917108D03*
Y967108D03*
Y1017108D03*
Y1067108D03*
Y1117108D03*
Y1167108D03*
Y1217108D03*
Y1267108D03*
Y1317108D03*
Y1367108D03*
Y1417108D03*
Y1467108D03*
Y1517108D03*
Y1567108D03*
Y1617108D03*
Y1667108D03*
Y1717108D03*
Y1767108D03*
Y1817108D03*
Y1867108D03*
Y1917108D03*
Y1967108D03*
Y2017108D03*
Y2067108D03*
G54D30*
X173385Y32520D03*
Y21890D03*
X183385Y32520D03*
Y21890D03*
X193385Y32520D03*
Y21890D03*
X173385Y196890D03*
X183385D03*
X193385D03*
X173385Y207520D03*
X183385D03*
X193385D03*
X173385Y371890D03*
X183385D03*
X193385D03*
X173385Y382520D03*
X183385D03*
X193385D03*
X173386Y557520D03*
Y546890D03*
X183386Y557520D03*
Y546890D03*
X193386Y557520D03*
Y546890D03*
X173386Y732520D03*
Y721890D03*
X183386Y732520D03*
Y721890D03*
X193386Y732520D03*
Y721890D03*
X173385Y896890D03*
X183385D03*
X193385D03*
X173385Y907520D03*
X183385D03*
X193385D03*
X173385Y1071890D03*
X183385D03*
X193385D03*
X173385Y1082520D03*
X183385D03*
X193385D03*
X173385Y1257520D03*
Y1246890D03*
X183385Y1257520D03*
Y1246890D03*
X193385Y1257520D03*
Y1246890D03*
X173385Y1432520D03*
Y1421890D03*
X183385Y1432520D03*
Y1421890D03*
X193385Y1432520D03*
Y1421890D03*
X173385Y1596890D03*
X183385D03*
X193385D03*
X173385Y1607520D03*
X183385D03*
X193385D03*
X173385Y1771890D03*
X183385D03*
X193385D03*
X173385Y1782520D03*
X183385D03*
X193385D03*
X173385Y1957520D03*
Y1946890D03*
X183385Y1957520D03*
Y1946890D03*
X193385Y1957520D03*
Y1946890D03*
X203385Y32520D03*
Y21890D03*
X213385Y32520D03*
Y21890D03*
X203385Y196890D03*
X213385D03*
X203385Y207520D03*
X213385D03*
X203385Y371890D03*
X213385D03*
X203385Y382520D03*
X213385D03*
X203386Y557520D03*
Y546890D03*
X213386Y557520D03*
Y546890D03*
X203386Y732520D03*
Y721890D03*
X213386Y732520D03*
Y721890D03*
X203385Y896890D03*
X213385D03*
X203385Y907520D03*
X213385D03*
X203385Y1071890D03*
X213385D03*
X203385Y1082520D03*
X213385D03*
X203385Y1257520D03*
Y1246890D03*
X213385Y1257520D03*
Y1246890D03*
X203385Y1432520D03*
Y1421890D03*
X213385Y1432520D03*
Y1421890D03*
X203385Y1596890D03*
X213385D03*
X203385Y1607520D03*
X213385D03*
X203385Y1771890D03*
X213385D03*
X203385Y1782520D03*
X213385D03*
X203385Y1957520D03*
Y1946890D03*
X213385Y1957520D03*
Y1946890D03*
X223385Y32520D03*
Y21890D03*
X233385Y32520D03*
Y21890D03*
X243385Y32520D03*
Y21890D03*
X223385Y196890D03*
X233385D03*
X243385D03*
X223385Y207520D03*
X233385D03*
X243385D03*
X223385Y371890D03*
X233385D03*
X243385D03*
X223385Y382520D03*
X233385D03*
X243385D03*
X223386Y557520D03*
Y546890D03*
X233386Y557520D03*
Y546890D03*
X243386Y557520D03*
Y546890D03*
X223386Y732520D03*
Y721890D03*
X233386Y732520D03*
Y721890D03*
X243386Y732520D03*
Y721890D03*
X223385Y896890D03*
X233385D03*
X243385D03*
X223385Y907520D03*
X233385D03*
X243385D03*
X223385Y1071890D03*
X233385D03*
X243385D03*
X223385Y1082520D03*
X233385D03*
X243385D03*
X223385Y1257520D03*
Y1246890D03*
X233385Y1257520D03*
Y1246890D03*
X243385Y1257520D03*
Y1246890D03*
X223385Y1432520D03*
Y1421890D03*
X233385Y1432520D03*
Y1421890D03*
X243385Y1432520D03*
Y1421890D03*
X223385Y1596890D03*
X233385D03*
X243385D03*
X223385Y1607520D03*
X233385D03*
X243385D03*
X223385Y1771890D03*
X233385D03*
X243385D03*
X223385Y1782520D03*
X233385D03*
X243385D03*
X223385Y1957520D03*
Y1946890D03*
X233385Y1957520D03*
Y1946890D03*
X243385Y1957520D03*
Y1946890D03*
X337165Y24705D03*
Y34705D03*
Y199705D03*
Y209705D03*
Y374705D03*
Y384705D03*
X337166Y549705D03*
Y559705D03*
Y724705D03*
Y734705D03*
X337165Y899705D03*
Y909705D03*
Y1074705D03*
Y1084705D03*
Y1249705D03*
Y1259705D03*
Y1424705D03*
Y1434705D03*
Y1599705D03*
Y1609705D03*
Y1774705D03*
Y1784705D03*
Y1949705D03*
Y1959705D03*
X342165Y19705D03*
Y29705D03*
X347165Y24705D03*
X352165Y19705D03*
Y29705D03*
X357165Y24705D03*
X362165Y19705D03*
Y29705D03*
X347165Y34705D03*
X357165D03*
X342165Y194705D03*
X347165Y199705D03*
X352165Y194705D03*
X357165Y199705D03*
X362165Y194705D03*
X342165Y204705D03*
X347165Y209705D03*
X352165Y204705D03*
X357165Y209705D03*
X362165Y204705D03*
X342165Y369705D03*
X352165D03*
X362165D03*
X342165Y379705D03*
X347165Y374705D03*
Y384705D03*
X352165Y379705D03*
X357165Y374705D03*
Y384705D03*
X362165Y379705D03*
X342166Y544705D03*
Y554705D03*
X347166Y549705D03*
Y559705D03*
X352166Y544705D03*
Y554705D03*
X357166Y549705D03*
Y559705D03*
X362166Y544705D03*
Y554705D03*
X342166Y719705D03*
Y729705D03*
X347166Y724705D03*
X352166Y719705D03*
Y729705D03*
X357166Y724705D03*
X362166Y719705D03*
Y729705D03*
X347166Y734705D03*
X357166D03*
X342165Y894705D03*
X347165Y899705D03*
X352165Y894705D03*
X357165Y899705D03*
X362165Y894705D03*
X342165Y904705D03*
X347165Y909705D03*
X352165Y904705D03*
X357165Y909705D03*
X362165Y904705D03*
X342165Y1069705D03*
X352165D03*
X362165D03*
X342165Y1079705D03*
X347165Y1074705D03*
Y1084705D03*
X352165Y1079705D03*
X357165Y1074705D03*
Y1084705D03*
X362165Y1079705D03*
X342165Y1244705D03*
Y1254705D03*
X347165Y1249705D03*
Y1259705D03*
X352165Y1244705D03*
Y1254705D03*
X357165Y1249705D03*
Y1259705D03*
X362165Y1244705D03*
Y1254705D03*
X342165Y1419705D03*
Y1429705D03*
X347165Y1424705D03*
Y1434705D03*
X352165Y1419705D03*
Y1429705D03*
X357165Y1424705D03*
Y1434705D03*
X362165Y1419705D03*
Y1429705D03*
X342165Y1594705D03*
X347165Y1599705D03*
X352165Y1594705D03*
X357165Y1599705D03*
X362165Y1594705D03*
X342165Y1604705D03*
X347165Y1609705D03*
X352165Y1604705D03*
X357165Y1609705D03*
X362165Y1604705D03*
X342165Y1769705D03*
X352165D03*
X362165D03*
X342165Y1779705D03*
X347165Y1774705D03*
Y1784705D03*
X352165Y1779705D03*
X357165Y1774705D03*
Y1784705D03*
X362165Y1779705D03*
X342165Y1944705D03*
Y1954705D03*
X347165Y1949705D03*
Y1959705D03*
X352165Y1944705D03*
Y1954705D03*
X357165Y1949705D03*
Y1959705D03*
X362165Y1944705D03*
Y1954705D03*
G54D24*
X65354Y101180D03*
X55511Y105117D03*
X51574Y114960D03*
X55511Y124803D03*
X65354Y128740D03*
Y451180D03*
X55511Y455117D03*
X51574Y464960D03*
X55511Y474803D03*
X65354Y478740D03*
Y801180D03*
X55511Y805117D03*
X51574Y814960D03*
X55511Y824803D03*
X65354Y828740D03*
Y1151180D03*
X55511Y1155117D03*
X51574Y1164960D03*
X55511Y1174803D03*
X65354Y1178740D03*
Y1501180D03*
X55511Y1505117D03*
X51574Y1514960D03*
X55511Y1524803D03*
X65354Y1528740D03*
Y1851180D03*
X55511Y1855117D03*
X51574Y1864960D03*
X55511Y1874803D03*
X65354Y1878740D03*
X75197Y105117D03*
Y124803D03*
X79134Y114960D03*
Y464960D03*
X75197Y455117D03*
Y474803D03*
Y805117D03*
Y824803D03*
X79134Y814960D03*
Y1164960D03*
X75197Y1155117D03*
Y1174803D03*
Y1505117D03*
Y1524803D03*
X79134Y1514960D03*
Y1864960D03*
X75197Y1855117D03*
Y1874803D03*
X307086Y113385D03*
X297243Y117322D03*
X293306Y127165D03*
X297243Y137008D03*
X307086Y140945D03*
Y463385D03*
X297243Y467322D03*
X293306Y477165D03*
X297243Y487008D03*
X307086Y490945D03*
Y813385D03*
X297243Y817322D03*
X293306Y827165D03*
X297243Y837008D03*
X307086Y840945D03*
Y1329724D03*
X297243Y1333661D03*
X293306Y1343504D03*
X297243Y1353347D03*
X307086Y1357284D03*
Y1679724D03*
X297243Y1683661D03*
X293306Y1693504D03*
X297243Y1703347D03*
X307086Y1707284D03*
X307087Y2029723D03*
X297244Y2033660D03*
X293307Y2043503D03*
X297244Y2053346D03*
X307087Y2057283D03*
X320866Y127165D03*
X316929Y117322D03*
Y137008D03*
Y467322D03*
Y487008D03*
X320866Y477165D03*
Y827165D03*
X316929Y817322D03*
Y837008D03*
Y1333661D03*
Y1353347D03*
X320866Y1343504D03*
Y1693504D03*
X316929Y1683661D03*
Y1703347D03*
X316930Y2033660D03*
Y2053346D03*
X320867Y2043503D03*
G54D12*
X22756Y113818D03*
Y125629D03*
X22480Y316838D03*
Y340460D03*
X22756Y1866819D03*
Y1878630D03*
Y1948818D03*
Y1960629D03*
Y2023818D03*
Y2035629D03*
G54D20*
X30473Y102007D03*
Y137440D03*
X30197Y305027D03*
Y352271D03*
X30473Y1855008D03*
Y1890441D03*
Y1937007D03*
Y1972440D03*
Y2012007D03*
Y2047440D03*
G54D27*
X119920Y18071D03*
Y28071D03*
Y38071D03*
Y48071D03*
Y58071D03*
Y68071D03*
Y78071D03*
Y88071D03*
Y98071D03*
Y108071D03*
Y118071D03*
Y128071D03*
Y138071D03*
Y148071D03*
Y158071D03*
Y168071D03*
Y178071D03*
Y188071D03*
Y198071D03*
Y208071D03*
Y366102D03*
Y376102D03*
Y386102D03*
Y396102D03*
Y406102D03*
Y416102D03*
Y426102D03*
Y436102D03*
Y446102D03*
Y456102D03*
Y466102D03*
Y476102D03*
Y486102D03*
Y496102D03*
Y506102D03*
Y516102D03*
Y526102D03*
Y536102D03*
Y546102D03*
Y556102D03*
Y714134D03*
Y724134D03*
Y734134D03*
Y744134D03*
Y754134D03*
Y764134D03*
Y774134D03*
Y784134D03*
Y794134D03*
Y804134D03*
Y814134D03*
Y824134D03*
Y834134D03*
Y844134D03*
Y854134D03*
Y864134D03*
Y874134D03*
Y884134D03*
Y894134D03*
Y904134D03*
Y1062165D03*
Y1072165D03*
Y1082165D03*
Y1092165D03*
Y1102165D03*
Y1112165D03*
Y1122165D03*
Y1132165D03*
Y1142165D03*
Y1152165D03*
Y1162165D03*
Y1172165D03*
Y1182165D03*
Y1192165D03*
Y1202165D03*
Y1212165D03*
Y1222165D03*
Y1232165D03*
Y1242165D03*
Y1252165D03*
Y1410197D03*
Y1420197D03*
Y1430197D03*
Y1440197D03*
Y1450197D03*
Y1460197D03*
Y1470197D03*
Y1480197D03*
Y1490197D03*
Y1500197D03*
Y1510197D03*
Y1520197D03*
Y1530197D03*
Y1540197D03*
Y1550197D03*
Y1560197D03*
Y1570197D03*
Y1580197D03*
Y1590197D03*
Y1600197D03*
Y1758228D03*
Y1768228D03*
Y1778228D03*
Y1788228D03*
Y1798228D03*
Y1808228D03*
Y1818228D03*
Y1828228D03*
Y1838228D03*
Y1848228D03*
Y1858228D03*
Y1868228D03*
Y1878228D03*
Y1888228D03*
Y1898228D03*
Y1908228D03*
Y1918228D03*
Y1928228D03*
Y1938228D03*
Y1948228D03*
X139920Y28071D03*
Y18071D03*
Y58071D03*
Y48071D03*
Y38071D03*
Y78071D03*
Y68071D03*
Y98071D03*
Y88071D03*
Y128071D03*
Y118071D03*
Y108071D03*
Y148071D03*
Y138071D03*
Y178071D03*
Y168071D03*
Y158071D03*
Y198071D03*
Y188071D03*
Y208071D03*
Y366102D03*
Y396102D03*
Y386102D03*
Y376102D03*
Y416102D03*
Y406102D03*
Y436102D03*
Y426102D03*
Y466102D03*
Y456102D03*
Y446102D03*
Y486102D03*
Y476102D03*
Y516102D03*
Y506102D03*
Y496102D03*
Y536102D03*
Y526102D03*
Y556102D03*
Y546102D03*
Y734134D03*
Y724134D03*
Y714134D03*
Y754134D03*
Y744134D03*
Y774134D03*
Y764134D03*
Y804134D03*
Y794134D03*
Y784134D03*
Y824134D03*
Y814134D03*
Y854134D03*
Y844134D03*
Y834134D03*
Y874134D03*
Y864134D03*
Y904134D03*
Y894134D03*
Y884134D03*
Y1072165D03*
Y1062165D03*
Y1092165D03*
Y1082165D03*
Y1122165D03*
Y1112165D03*
Y1102165D03*
Y1142165D03*
Y1132165D03*
Y1162165D03*
Y1152165D03*
Y1192165D03*
Y1182165D03*
Y1172165D03*
Y1212165D03*
Y1202165D03*
Y1242165D03*
Y1232165D03*
Y1222165D03*
Y1252165D03*
Y1410197D03*
Y1430197D03*
Y1420197D03*
Y1460197D03*
Y1450197D03*
Y1440197D03*
Y1480197D03*
Y1470197D03*
Y1500197D03*
Y1490197D03*
Y1530197D03*
Y1520197D03*
Y1510197D03*
Y1550197D03*
Y1540197D03*
Y1580197D03*
Y1570197D03*
Y1560197D03*
Y1600197D03*
Y1590197D03*
Y1768228D03*
Y1758228D03*
Y1798228D03*
Y1788228D03*
Y1778228D03*
Y1818228D03*
Y1808228D03*
Y1838228D03*
Y1828228D03*
Y1868228D03*
Y1858228D03*
Y1848228D03*
Y1888228D03*
Y1878228D03*
Y1918228D03*
Y1908228D03*
Y1898228D03*
Y1938228D03*
Y1928228D03*
Y1948228D03*
G54D14*
X14073Y512197D03*
Y522000D03*
Y552000D03*
Y561803D03*
Y1580004D03*
Y1570201D03*
Y1610004D03*
Y1619807D03*
X65254Y519500D03*
Y529500D03*
Y539500D03*
X55254Y524500D03*
Y534500D03*
X65254Y549500D03*
X55254Y544500D03*
Y554500D03*
X65254Y1577504D03*
Y1587504D03*
Y1597504D03*
X55254Y1582504D03*
Y1592504D03*
Y1602504D03*
X65254Y1607504D03*
X55254Y1612504D03*
X189762Y73105D03*
X190289Y152050D03*
X190357Y247568D03*
X190817Y331786D03*
X189761Y421732D03*
X190553Y506517D03*
X192888Y598130D03*
X190816Y681645D03*
X191846Y774526D03*
X191606Y856244D03*
X196311Y947202D03*
X195516Y1032544D03*
X191250Y1122856D03*
X191342Y1206233D03*
X191846Y1299104D03*
X190552Y1380966D03*
X189463Y1474162D03*
X191079Y1557277D03*
X192143Y1648177D03*
X191607Y1731351D03*
X191530Y1823227D03*
X190289Y1900420D03*
X192125Y1998730D03*
X191530Y2043388D03*
G54D21*
X45411Y505996D03*
Y568004D03*
Y1564000D03*
Y1626008D03*
G54D16*
X15547Y707364D03*
Y723112D03*
Y730986D03*
X25389Y723112D03*
Y730986D03*
X7673Y719175D03*
Y727049D03*
X15547Y738860D03*
Y746734D03*
Y754608D03*
X25389Y738860D03*
Y746734D03*
Y754608D03*
X7673Y734923D03*
Y742797D03*
Y750671D03*
Y758545D03*
X15547Y762483D03*
Y770357D03*
Y778231D03*
X25389Y762483D03*
Y770357D03*
Y778231D03*
X7673Y766419D03*
Y774293D03*
Y782167D03*
X15547Y786105D03*
Y793979D03*
Y801853D03*
X25389Y786105D03*
Y793979D03*
Y801853D03*
X7673Y790041D03*
Y797915D03*
Y805790D03*
X15547Y809727D03*
Y817601D03*
Y825475D03*
X25389Y809727D03*
Y817601D03*
Y825475D03*
X7673Y813664D03*
Y821538D03*
Y829412D03*
X15547Y833349D03*
Y841223D03*
Y849097D03*
X25389Y833349D03*
Y841223D03*
Y849097D03*
X7673Y837286D03*
Y845160D03*
Y853034D03*
X15547Y856971D03*
Y864845D03*
Y872719D03*
X25389Y856971D03*
Y864845D03*
Y872719D03*
X7673Y860908D03*
Y868782D03*
Y876656D03*
X15547Y880593D03*
Y888467D03*
Y896341D03*
X25389Y880593D03*
Y888467D03*
Y896341D03*
X7673Y884530D03*
Y892404D03*
Y900278D03*
X15547Y904215D03*
Y912089D03*
Y919963D03*
X25389Y904215D03*
Y912089D03*
Y919963D03*
X7673Y908152D03*
Y916026D03*
Y923900D03*
X15547Y927837D03*
Y935711D03*
Y943585D03*
Y951459D03*
X25389Y927837D03*
Y935711D03*
Y943585D03*
Y951459D03*
X7673Y931774D03*
Y939648D03*
Y947522D03*
X15547Y959333D03*
Y967207D03*
Y975081D03*
X25389Y959333D03*
Y967207D03*
Y975081D03*
X7673Y955396D03*
Y963270D03*
Y971144D03*
Y979018D03*
Y994766D03*
X15547Y990829D03*
Y998703D03*
X25389Y990829D03*
Y998703D03*
X7673Y1002640D03*
Y1010514D03*
Y1018388D03*
X15547Y1006577D03*
Y1014451D03*
Y1022325D03*
X25389Y1006577D03*
Y1014451D03*
Y1022325D03*
X7673Y1026262D03*
X15547Y1030199D03*
X25389D03*
X15551Y1065629D03*
X25393D03*
X7677Y1061692D03*
Y1069566D03*
X15551Y1073503D03*
Y1081377D03*
Y1089251D03*
X25393Y1073503D03*
Y1081377D03*
Y1089251D03*
X7677Y1077440D03*
Y1085314D03*
Y1093188D03*
X15551Y1097125D03*
Y1104999D03*
Y1112873D03*
Y1120748D03*
X25393Y1097125D03*
Y1104999D03*
Y1112873D03*
Y1120748D03*
X7677Y1101062D03*
Y1108936D03*
Y1116810D03*
X15551Y1128622D03*
Y1136496D03*
Y1144370D03*
X25393Y1128622D03*
Y1136496D03*
Y1144370D03*
X7677Y1124684D03*
Y1132558D03*
Y1140432D03*
X15551Y1152244D03*
Y1160118D03*
Y1167992D03*
X25393Y1152244D03*
Y1160118D03*
Y1167992D03*
X7677Y1148306D03*
Y1156180D03*
Y1164055D03*
X15551Y1175866D03*
Y1183740D03*
Y1191614D03*
X25393Y1175866D03*
Y1183740D03*
Y1191614D03*
X7677Y1171929D03*
Y1179803D03*
Y1187677D03*
X15551Y1199488D03*
Y1207362D03*
Y1215236D03*
X25393Y1199488D03*
Y1207362D03*
Y1215236D03*
X7677Y1195551D03*
Y1203425D03*
Y1211299D03*
X15551Y1223110D03*
Y1230984D03*
Y1238858D03*
X25393Y1223110D03*
Y1230984D03*
Y1238858D03*
X7677Y1219173D03*
Y1227047D03*
Y1234921D03*
X15551Y1246732D03*
Y1254606D03*
Y1262480D03*
X25393Y1246732D03*
Y1254606D03*
Y1262480D03*
X7677Y1242795D03*
Y1250669D03*
Y1258543D03*
X15551Y1270354D03*
Y1278228D03*
Y1286102D03*
X25393Y1270354D03*
Y1278228D03*
Y1286102D03*
X7677Y1266417D03*
Y1274291D03*
Y1282165D03*
X15551Y1293976D03*
Y1301850D03*
Y1309724D03*
X25393Y1293976D03*
Y1301850D03*
Y1309724D03*
X7677Y1290039D03*
Y1297913D03*
Y1305787D03*
Y1313661D03*
X15551Y1317598D03*
Y1325472D03*
Y1333346D03*
X25393Y1317598D03*
Y1325472D03*
Y1333346D03*
X7677Y1321535D03*
Y1329409D03*
Y1337283D03*
Y1353031D03*
Y1360905D03*
X15551Y1349094D03*
Y1356968D03*
X25393Y1349094D03*
Y1356968D03*
X7677Y1368779D03*
Y1376653D03*
Y1384527D03*
X15551Y1364842D03*
Y1372716D03*
Y1380590D03*
X25393Y1364842D03*
Y1372716D03*
Y1380590D03*
X15551Y1388464D03*
X25393D03*
X33263Y727049D03*
Y734923D03*
Y742797D03*
Y750671D03*
Y758545D03*
Y766419D03*
Y774293D03*
Y782167D03*
Y790041D03*
Y797915D03*
Y805790D03*
Y813664D03*
Y821538D03*
Y829412D03*
Y837286D03*
Y845160D03*
Y853034D03*
Y860908D03*
Y868782D03*
Y876656D03*
Y884530D03*
Y892404D03*
Y900278D03*
Y908152D03*
Y916026D03*
Y923900D03*
Y931774D03*
Y939648D03*
Y947522D03*
Y955396D03*
Y963270D03*
Y971144D03*
Y979018D03*
Y994766D03*
Y1002640D03*
Y1010514D03*
Y1018388D03*
Y1026262D03*
X33267Y1061692D03*
Y1069566D03*
Y1077440D03*
Y1085314D03*
Y1093188D03*
Y1101062D03*
Y1108936D03*
Y1116810D03*
Y1124684D03*
Y1132558D03*
Y1140432D03*
Y1148306D03*
Y1156180D03*
Y1164055D03*
Y1171929D03*
Y1179803D03*
Y1187677D03*
Y1195551D03*
Y1203425D03*
Y1211299D03*
Y1219173D03*
Y1227047D03*
Y1234921D03*
Y1242795D03*
Y1250669D03*
Y1258543D03*
Y1266417D03*
Y1274291D03*
Y1282165D03*
Y1290039D03*
Y1297913D03*
Y1305787D03*
Y1313661D03*
Y1321535D03*
Y1329409D03*
Y1337283D03*
Y1353031D03*
Y1360905D03*
Y1368779D03*
Y1376653D03*
Y1384527D03*
G54D19*
X23402Y1668874D03*
Y1685410D03*
Y1701945D03*
Y1718480D03*
Y1735016D03*
Y1751551D03*
Y1768087D03*
Y1784622D03*
Y1817693D03*
Y1801158D03*
X45056Y1668874D03*
Y1718480D03*
Y1768087D03*
Y1817693D03*
G54D23*
X64979Y35500D03*
Y45500D03*
Y55500D03*
X54979Y40500D03*
Y50500D03*
X64979Y65500D03*
X54979Y60500D03*
Y70500D03*
X64979Y171500D03*
X54979Y176500D03*
X64979Y181500D03*
Y191500D03*
Y201500D03*
X54979Y186500D03*
Y196500D03*
Y206500D03*
X64979Y244500D03*
X54979Y249500D03*
X64979Y254500D03*
Y264500D03*
Y274500D03*
X54979Y259500D03*
Y269500D03*
Y279500D03*
X64979Y380500D03*
Y390500D03*
X54979Y385500D03*
Y395500D03*
X64979Y400500D03*
Y410500D03*
X54979Y405500D03*
Y415500D03*
G54D13*
X22480Y328649D03*
G54D34*
X307086Y1883071D03*
G54D18*
X20468Y696341D03*
Y984333D03*
X20472Y1054606D03*
Y1342598D03*
G54D10*
X29979Y30500D03*
Y75500D03*
Y166500D03*
Y211500D03*
Y239500D03*
Y284500D03*
Y375500D03*
Y420500D03*
G54D33*
X307086Y308267D03*
G54D15*
X30254Y514500D03*
Y559500D03*
Y1572504D03*
Y1617504D03*
G54D29*
X163385Y27205D03*
Y202205D03*
Y377205D03*
X163386Y552205D03*
Y727205D03*
X163385Y902205D03*
Y1077205D03*
Y1252205D03*
Y1427205D03*
Y1602205D03*
Y1777205D03*
Y1952205D03*
X373385Y32520D03*
Y207520D03*
Y382520D03*
X373386Y557520D03*
Y732520D03*
X373385Y907520D03*
Y1082520D03*
Y1257520D03*
Y1432520D03*
Y1607520D03*
Y1782520D03*
Y1957520D03*
G54D35*
X359842Y78780D03*
Y253780D03*
Y428779D03*
Y603779D03*
Y778780D03*
Y953780D03*
Y1128779D03*
Y1303780D03*
Y1478780D03*
Y1653780D03*
Y1828779D03*
Y2003780D03*
G54D17*
X25389Y707364D03*
X7673Y703427D03*
X15547Y715238D03*
X25389D03*
X7673Y711301D03*
X33263Y703427D03*
Y711301D03*
Y719175D03*
G54D32*
X253385Y21890D03*
Y32520D03*
X263385Y21890D03*
Y32520D03*
X253385Y196890D03*
X263385D03*
X253385Y207520D03*
X263385D03*
X253385Y371890D03*
X263385D03*
X253385Y382520D03*
X263385D03*
X253386Y546890D03*
Y557520D03*
X263386Y546890D03*
Y557520D03*
X253386Y721890D03*
Y732520D03*
X263386Y721890D03*
Y732520D03*
X253385Y896890D03*
X263385D03*
X253385Y907520D03*
X263385D03*
X253385Y1071890D03*
X263385D03*
X253385Y1082520D03*
X263385D03*
X253385Y1246890D03*
Y1257520D03*
X263385Y1246890D03*
Y1257520D03*
X253385Y1421890D03*
Y1432520D03*
X263385Y1421890D03*
Y1432520D03*
X253385Y1596890D03*
X263385D03*
X253385Y1607520D03*
X263385D03*
X253385Y1771890D03*
X263385D03*
X253385Y1782520D03*
X263385D03*
X253385Y1946890D03*
Y1957520D03*
X263385Y1946890D03*
Y1957520D03*
X273385Y21890D03*
Y32520D03*
X283385Y21890D03*
Y32520D03*
X273385Y196890D03*
X283385D03*
X273385Y207520D03*
X283385D03*
X273385Y371890D03*
X283385D03*
X273385Y382520D03*
X283385D03*
X273386Y546890D03*
Y557520D03*
X283386Y546890D03*
Y557520D03*
X273386Y721890D03*
Y732520D03*
X283386Y721890D03*
Y732520D03*
X273385Y896890D03*
X283385D03*
X273385Y907520D03*
X283385D03*
X273385Y1071890D03*
X283385D03*
X273385Y1082520D03*
X283385D03*
X273385Y1246890D03*
Y1257520D03*
X283385Y1246890D03*
Y1257520D03*
X273385Y1421890D03*
Y1432520D03*
X283385Y1421890D03*
Y1432520D03*
X273385Y1596890D03*
X283385D03*
X273385Y1607520D03*
X283385D03*
X273385Y1771890D03*
X283385D03*
X273385Y1782520D03*
X283385D03*
X273385Y1946890D03*
Y1957520D03*
X283385Y1946890D03*
Y1957520D03*
X293385Y21890D03*
Y32520D03*
X303385Y21890D03*
Y32520D03*
X313385D03*
Y21890D03*
X293385Y196890D03*
X303385D03*
X313385D03*
X293385Y207520D03*
X303385D03*
X313385D03*
X293385Y371890D03*
X303385D03*
X313385D03*
X293385Y382520D03*
X303385D03*
X313385D03*
X293386Y546890D03*
Y557520D03*
X303386Y546890D03*
Y557520D03*
X313386D03*
Y546890D03*
X293386Y721890D03*
Y732520D03*
X303386Y721890D03*
Y732520D03*
X313386D03*
Y721890D03*
X293385Y896890D03*
X303385D03*
X313385D03*
X293385Y907520D03*
X303385D03*
X313385D03*
X293385Y1071890D03*
X303385D03*
X313385D03*
X293385Y1082520D03*
X303385D03*
X313385D03*
X293385Y1246890D03*
Y1257520D03*
X303385Y1246890D03*
Y1257520D03*
X313385D03*
Y1246890D03*
X293385Y1421890D03*
Y1432520D03*
X303385Y1421890D03*
Y1432520D03*
X313385D03*
Y1421890D03*
X293385Y1596890D03*
X303385D03*
X313385D03*
X293385Y1607520D03*
X303385D03*
X313385D03*
X293385Y1771890D03*
X303385D03*
X313385D03*
X293385Y1782520D03*
X303385D03*
X313385D03*
X293385Y1946890D03*
Y1957520D03*
X303385Y1946890D03*
Y1957520D03*
X313385D03*
Y1946890D03*
X323385Y32520D03*
Y21890D03*
Y196890D03*
Y207520D03*
Y371890D03*
Y382520D03*
X323386Y557520D03*
Y546890D03*
Y732520D03*
Y721890D03*
X323385Y896890D03*
Y907520D03*
Y1071890D03*
Y1082520D03*
Y1257520D03*
Y1246890D03*
Y1432520D03*
Y1421890D03*
Y1596890D03*
Y1607520D03*
Y1771890D03*
Y1782520D03*
Y1957520D03*
Y1946890D03*
G54D25*
X65354Y114960D03*
Y464960D03*
Y814960D03*
Y1164960D03*
Y1514960D03*
Y1864960D03*
X307086Y127165D03*
Y477165D03*
Y827165D03*
Y1343504D03*
Y1693504D03*
X307087Y2043503D03*
G54D26*
X59127Y1257647D03*
X58356Y1279812D03*
X58416Y1272383D03*
X161339Y88108D03*
X168975Y265783D03*
X165975D03*
X168975Y296140D03*
Y286803D03*
Y276298D03*
X165975D03*
Y286803D03*
Y296140D03*
X168975Y312307D03*
Y303868D03*
X165975D03*
Y312307D03*
X161517Y436119D03*
X157272Y604773D03*
X160272D03*
X157272Y633416D03*
Y613574D03*
Y624079D03*
X160272D03*
Y613574D03*
Y633416D03*
X157272Y641144D03*
Y649583D03*
X160272D03*
Y641144D03*
X161479Y784141D03*
X163699Y972924D03*
X166699D03*
X163699Y983439D03*
Y993944D03*
X166699D03*
Y983439D03*
X163424Y1011298D03*
Y1003570D03*
Y1019737D03*
X166424D03*
Y1003570D03*
Y1011298D03*
X158749Y1307733D03*
X155749D03*
X158749Y1328753D03*
Y1318248D03*
X155749D03*
Y1328753D03*
X158749Y1354257D03*
Y1338090D03*
Y1345818D03*
X155749D03*
Y1338090D03*
Y1354257D03*
X161492Y1667763D03*
Y1657248D03*
X158492D03*
Y1667763D03*
X161492Y1695333D03*
Y1687605D03*
Y1678268D03*
X158492D03*
Y1687605D03*
Y1695333D03*
X161492Y1703772D03*
X158492D03*
X161844Y1828225D03*
X217732Y153964D03*
Y170131D03*
Y161692D03*
Y164692D03*
Y173131D03*
Y156964D03*
X219214Y1287272D03*
Y1301975D03*
X219349Y1308924D03*
X219214Y1294491D03*
X219178Y1324285D03*
Y1332321D03*
Y1316842D03*
Y1339840D03*
X238741Y153964D03*
X227700D03*
X238741Y170131D03*
Y161692D03*
X227700Y170131D03*
Y161692D03*
Y164692D03*
Y173131D03*
X238741Y164692D03*
Y173131D03*
X227700Y156964D03*
X238741D03*
X239746Y407393D03*
Y396878D03*
Y417898D03*
Y399878D03*
Y410393D03*
Y420898D03*
X234012Y754782D03*
X237012D03*
X234012Y762510D03*
Y770949D03*
X237012D03*
Y762510D03*
X241396Y862887D03*
Y855159D03*
Y871326D03*
X238396D03*
Y855159D03*
Y862887D03*
X235709Y1124900D03*
Y1135415D03*
X232709D03*
Y1124900D03*
X242677Y1135415D03*
Y1124900D03*
X235709Y1145920D03*
X232709D03*
X242677D03*
X226642Y1287272D03*
X222214D03*
X229642D03*
X226642Y1301975D03*
X235465D03*
X226777Y1308924D03*
X235600D03*
X242961Y1301975D03*
X243096Y1308924D03*
X226642Y1294491D03*
X235465D03*
X242961D03*
X222214D03*
X222349Y1308924D03*
X222214Y1301975D03*
X238465Y1294491D03*
X229642D03*
X238600Y1308924D03*
X229777D03*
X238465Y1301975D03*
X229642D03*
X226606Y1324285D03*
X235429D03*
X226606Y1332321D03*
X235429D03*
X242925Y1324285D03*
Y1332321D03*
X226606Y1316842D03*
X235429D03*
X242925D03*
X222178D03*
Y1332321D03*
Y1324285D03*
X238429Y1316842D03*
X229606D03*
X238429Y1332321D03*
X229606D03*
X238429Y1324285D03*
X229606D03*
X226606Y1339840D03*
X235429D03*
X242925D03*
X222178D03*
X238429D03*
X229606D03*
X226573Y2031480D03*
X236541D03*
X226573Y2020965D03*
X236541D03*
X242582D03*
Y2031480D03*
X231541Y2020965D03*
X221573D03*
X231541Y2031480D03*
X221573D03*
X226573Y2059050D03*
X236541Y2051322D03*
Y2059050D03*
X226573Y2041985D03*
Y2051322D03*
X236541Y2041985D03*
X242582Y2059050D03*
Y2051322D03*
Y2041985D03*
X231541D03*
X221573Y2051322D03*
Y2041985D03*
X231541Y2059050D03*
Y2051322D03*
X221573Y2059050D03*
X236541Y2067489D03*
X226573D03*
X242582D03*
X221573D03*
X231541D03*
X256566Y54944D03*
X264104D03*
X256566Y45572D03*
X264104D03*
Y48572D03*
X256566D03*
Y65449D03*
X264104D03*
Y57944D03*
X256566D03*
X264104Y68449D03*
X256566D03*
X256861Y153964D03*
X248083D03*
X256861Y170131D03*
Y161692D03*
X248083Y170131D03*
Y161692D03*
Y164692D03*
Y173131D03*
X256861Y164692D03*
Y173131D03*
X248083Y156964D03*
X256861D03*
X264596Y221664D03*
X252818D03*
X255818D03*
X261596D03*
X264596Y242684D03*
Y232179D03*
X252818Y242684D03*
Y232179D03*
X255818D03*
Y242684D03*
X261596Y232179D03*
Y242684D03*
X264596Y268188D03*
Y259749D03*
Y252021D03*
X252818Y268188D03*
Y252021D03*
Y259749D03*
X255818D03*
Y252021D03*
Y268188D03*
X261596Y252021D03*
Y259749D03*
Y268188D03*
X266040Y407146D03*
Y396631D03*
Y417651D03*
X257572Y396630D03*
Y407145D03*
X248714Y407536D03*
Y397021D03*
X257572Y417650D03*
X248714Y418041D03*
Y400021D03*
Y410536D03*
X257572Y410145D03*
Y399630D03*
X266040Y399631D03*
Y410146D03*
X248714Y421041D03*
X257572Y420650D03*
X266040Y420651D03*
X267166Y581440D03*
Y572639D03*
X264166D03*
Y581440D03*
X267166Y609010D03*
Y601282D03*
Y591945D03*
X264166D03*
Y601282D03*
Y609010D03*
X267166Y617449D03*
X264166D03*
X243980Y754782D03*
X255021D03*
X258021D03*
X246980D03*
X243980Y762510D03*
Y770949D03*
X255021Y762510D03*
Y770949D03*
X258021D03*
Y762510D03*
X246980Y770949D03*
Y762510D03*
X253174Y855159D03*
Y862887D03*
Y871326D03*
X250174D03*
Y862887D03*
Y855159D03*
X265766Y949344D03*
X262766D03*
X265766Y967106D03*
Y959859D03*
X265621Y974386D03*
X262621D03*
X262766Y959859D03*
Y967106D03*
X265621Y990553D03*
Y982114D03*
X262621D03*
Y990553D03*
X263473Y1124613D03*
Y1135128D03*
X245677Y1124900D03*
Y1135415D03*
X254433Y1135271D03*
Y1124756D03*
X251433D03*
Y1135271D03*
X260473Y1135128D03*
Y1124613D03*
X263473Y1145633D03*
X245677Y1145920D03*
X254433Y1145776D03*
X251433D03*
X260473Y1145633D03*
X259581Y1272430D03*
Y1282945D03*
X256581D03*
Y1272430D03*
X267622D03*
Y1282945D03*
X245961Y1294491D03*
X246096Y1308924D03*
X245961Y1301975D03*
X259581Y1293450D03*
Y1302787D03*
Y1310515D03*
X256581D03*
Y1302787D03*
Y1293450D03*
X267622Y1310515D03*
Y1302787D03*
Y1293450D03*
X245925Y1316842D03*
Y1332321D03*
Y1324285D03*
X259581Y1318954D03*
X256581D03*
X267622D03*
X245925Y1339840D03*
X260939Y1548010D03*
Y1534139D03*
Y1541055D03*
X263939D03*
Y1534139D03*
Y1548010D03*
X258564Y1621823D03*
X261564D03*
X258564Y1642843D03*
Y1632338D03*
X261564D03*
Y1642843D03*
X258564Y1668347D03*
Y1659908D03*
Y1652180D03*
X261564D03*
Y1659908D03*
Y1668347D03*
X262759Y1697613D03*
Y1676593D03*
Y1687108D03*
X251718Y1697613D03*
Y1687108D03*
Y1676593D03*
X254718D03*
Y1687108D03*
X265759D03*
Y1676593D03*
X254718Y1697613D03*
X265759D03*
X262498Y1722140D03*
X262759Y1714678D03*
Y1706950D03*
X251457Y1722140D03*
X251718Y1714678D03*
Y1706950D03*
X265759D03*
X254718D03*
Y1714678D03*
X265759D03*
X265498Y1722140D03*
X254457D03*
X261639Y1819074D03*
Y1812119D03*
Y1805203D03*
X253468Y1819074D03*
Y1812119D03*
Y1805203D03*
X267396Y1812122D03*
Y1805206D03*
Y1819077D03*
X250468Y1805203D03*
Y1812119D03*
Y1819074D03*
X258639Y1805203D03*
Y1812119D03*
Y1819074D03*
X261459Y1826219D03*
X253288D03*
X261459Y1840090D03*
Y1833135D03*
X253288D03*
Y1840090D03*
X250288D03*
Y1833135D03*
X267037Y1840093D03*
Y1833138D03*
X258459Y1833135D03*
Y1840090D03*
X267037Y1826222D03*
X250288Y1826219D03*
X258459D03*
X247582Y2031480D03*
Y2020965D03*
X260337D03*
Y2031480D03*
X267115Y2020965D03*
Y2031480D03*
X255337D03*
Y2020965D03*
X247582Y2041985D03*
Y2051322D03*
Y2059050D03*
X260337Y2051322D03*
Y2059050D03*
Y2041985D03*
X267115D03*
Y2059050D03*
Y2051322D03*
X255337Y2041985D03*
Y2059050D03*
Y2051322D03*
X260337Y2067489D03*
X247582D03*
X267115D03*
X255337D03*
X288102Y54944D03*
Y45572D03*
X271572Y54944D03*
X279754D03*
X271572Y45572D03*
X279754D03*
Y48572D03*
X271572D03*
X288102D03*
Y65449D03*
X271572D03*
X279754D03*
Y57944D03*
X271572D03*
X288102D03*
X279754Y68449D03*
X271572D03*
X288102D03*
X274531Y407289D03*
Y396774D03*
Y417794D03*
Y399774D03*
Y410289D03*
Y420794D03*
X289569Y532762D03*
Y516595D03*
Y524323D03*
X278944Y581440D03*
Y572639D03*
X275944D03*
Y581440D03*
X278944Y601282D03*
Y609010D03*
Y591945D03*
X275944D03*
Y609010D03*
Y601282D03*
X278944Y617449D03*
X275944D03*
X277544Y949344D03*
X274544D03*
X277544Y967106D03*
Y959859D03*
X277399Y974386D03*
X274399D03*
X274544Y959859D03*
Y967106D03*
X277399Y990553D03*
Y982114D03*
X274399D03*
Y990553D03*
X272821Y1124471D03*
Y1134986D03*
X269821D03*
Y1124471D03*
X272821Y1145491D03*
X269821D03*
X284182Y1184455D03*
Y1192183D03*
X287182D03*
Y1184455D03*
X284182Y1200622D03*
X287182D03*
X270622Y1282945D03*
Y1272430D03*
Y1293450D03*
Y1302787D03*
Y1310515D03*
Y1318954D03*
X275400Y1548190D03*
X268534Y1548010D03*
X282995Y1548190D03*
X275400Y1534319D03*
Y1541235D03*
X268534Y1534139D03*
Y1541055D03*
X282995Y1534319D03*
Y1541235D03*
X285995D03*
Y1534319D03*
X271534Y1541055D03*
Y1534139D03*
X278400Y1541235D03*
Y1534319D03*
X285995Y1548190D03*
X271534Y1548010D03*
X278400Y1548190D03*
X270342Y1621823D03*
X273342D03*
X270342Y1642843D03*
Y1632338D03*
X273342D03*
Y1642843D03*
X270342Y1668347D03*
Y1652180D03*
Y1659908D03*
X273342D03*
Y1652180D03*
Y1668347D03*
X270396Y1819077D03*
Y1805206D03*
Y1812122D03*
X270037Y1826222D03*
Y1833138D03*
Y1840093D03*
X272115Y2031480D03*
Y2020965D03*
Y2051322D03*
Y2059050D03*
Y2041985D03*
Y2067489D03*
X300537Y516309D03*
X307966Y516419D03*
Y524147D03*
X300537Y524037D03*
Y532476D03*
X307966Y532586D03*
X292569Y524323D03*
Y516595D03*
Y532762D03*
X304966Y532586D03*
X297537Y532476D03*
Y524037D03*
X304966Y524147D03*
Y516419D03*
X297537Y516309D03*
X313791Y532871D03*
Y516704D03*
Y524432D03*
X315187Y652457D03*
X304146D03*
X307146D03*
X315187Y661258D03*
X304146D03*
Y681100D03*
X315187D03*
Y671763D03*
X304146D03*
X307146D03*
Y681100D03*
Y661258D03*
X315187Y688828D03*
X304146D03*
Y697267D03*
X315187D03*
X307146D03*
Y688828D03*
X310194Y1020657D03*
X310078Y1007303D03*
X310274Y1001286D03*
X310143Y1014094D03*
X307143D03*
X307274Y1001286D03*
X307078Y1007303D03*
X307194Y1020657D03*
X310129Y1027081D03*
X309999Y1033718D03*
X306999D03*
X307129Y1027081D03*
X309159Y1184526D03*
Y1192254D03*
X300691Y1184526D03*
X292721Y1184312D03*
Y1192040D03*
X300691Y1192254D03*
X303691D03*
X295721Y1192040D03*
Y1184312D03*
X303691Y1184526D03*
X312159Y1192254D03*
Y1184526D03*
X309159Y1200693D03*
X300691D03*
X292721Y1200479D03*
X295721D03*
X303691Y1200693D03*
X312159D03*
X312823Y1472957D03*
X312464Y1480102D03*
X312823Y1466002D03*
Y1459086D03*
X295715Y1480099D03*
X295895Y1472954D03*
X304066D03*
X303886Y1480099D03*
X295895Y1459083D03*
Y1465999D03*
X304066D03*
Y1459083D03*
X301066D03*
Y1465999D03*
X292895D03*
Y1459083D03*
X300886Y1480099D03*
X301066Y1472954D03*
X292895D03*
X292715Y1480099D03*
X309823Y1459086D03*
Y1466002D03*
X309464Y1480102D03*
X309823Y1472957D03*
X312464Y1493973D03*
Y1487018D03*
X295715Y1487015D03*
Y1493970D03*
X303886D03*
Y1487015D03*
X300886D03*
Y1493970D03*
X292715D03*
Y1487015D03*
X309464Y1487018D03*
Y1493973D03*
X292614Y1864565D03*
X295754Y1917148D03*
X303349D03*
X295754Y1910232D03*
X303349D03*
X310215Y1910412D03*
X314810D03*
X307215D03*
X300349Y1910232D03*
X292754D03*
X300349Y1917148D03*
X292754D03*
X310215Y1917328D03*
X295754Y1924103D03*
X303349D03*
X310215Y1924283D03*
X307215D03*
X314810D03*
X300349Y1924103D03*
X292754D03*
X307215Y1917328D03*
X314810D03*
X332775Y318634D03*
X332693Y311980D03*
X329693D03*
X329775Y318634D03*
X332775Y335272D03*
Y342461D03*
Y325935D03*
X329775D03*
Y342461D03*
Y335272D03*
X332685Y348655D03*
X329685D03*
X325139Y516632D03*
Y524360D03*
X316791Y524432D03*
Y516704D03*
Y532871D03*
X325139Y532799D03*
X322139D03*
Y524360D03*
Y516632D03*
X318187Y652457D03*
Y671763D03*
Y681100D03*
Y661258D03*
Y697267D03*
Y688828D03*
X321235Y1020657D03*
X321315Y1001286D03*
X321119Y1007303D03*
X321184Y1014094D03*
X318184D03*
X318119Y1007303D03*
X318315Y1001286D03*
X318235Y1020657D03*
X321170Y1027081D03*
X321040Y1033718D03*
X318040D03*
X318170Y1027081D03*
X317936Y1192253D03*
Y1184525D03*
X320936D03*
Y1192253D03*
X323403Y1172804D03*
X317936Y1200692D03*
X320936D03*
X317810Y1910412D03*
Y1917328D03*
Y1924283D03*
X343816Y318634D03*
X343734Y311980D03*
X340734D03*
X340816Y318634D03*
X343816Y335272D03*
Y342461D03*
Y325935D03*
X340816D03*
Y342461D03*
Y335272D03*
X343726Y348655D03*
X340726D03*
G54D28*
X119920Y218071D03*
Y228071D03*
Y238071D03*
Y248071D03*
Y258071D03*
Y268071D03*
Y278071D03*
Y288071D03*
Y298071D03*
Y308071D03*
Y318071D03*
Y328071D03*
Y566102D03*
Y576102D03*
Y586102D03*
Y596102D03*
Y606102D03*
Y616102D03*
Y626102D03*
Y636102D03*
Y646102D03*
Y656102D03*
Y666102D03*
Y676102D03*
Y914134D03*
Y924134D03*
Y934134D03*
Y944134D03*
Y954134D03*
Y964134D03*
Y974134D03*
Y984134D03*
Y994134D03*
Y1004134D03*
Y1014134D03*
Y1024134D03*
Y1262165D03*
Y1272165D03*
Y1282165D03*
Y1292165D03*
Y1302165D03*
Y1312165D03*
Y1322165D03*
Y1332165D03*
Y1342165D03*
Y1352165D03*
Y1362165D03*
Y1372165D03*
Y1610197D03*
Y1620197D03*
Y1630197D03*
Y1640197D03*
Y1650197D03*
Y1660197D03*
Y1670197D03*
Y1680197D03*
Y1690197D03*
Y1700197D03*
Y1710197D03*
Y1720197D03*
Y1958228D03*
Y1968228D03*
Y1978228D03*
Y1988228D03*
Y1998228D03*
Y2008228D03*
Y2018228D03*
Y2028228D03*
Y2038228D03*
Y2048228D03*
Y2058228D03*
Y2068228D03*
X139920Y228071D03*
Y218071D03*
Y248071D03*
Y238071D03*
Y268071D03*
Y258071D03*
Y298071D03*
Y288071D03*
Y278071D03*
Y318071D03*
Y308071D03*
Y328071D03*
Y566102D03*
Y586102D03*
Y576102D03*
Y606102D03*
Y596102D03*
Y636102D03*
Y626102D03*
Y616102D03*
Y656102D03*
Y646102D03*
Y676102D03*
Y666102D03*
Y924134D03*
Y914134D03*
Y944134D03*
Y934134D03*
Y974134D03*
Y964134D03*
Y954134D03*
Y994134D03*
Y984134D03*
Y1024134D03*
Y1014134D03*
Y1004134D03*
Y1262165D03*
Y1282165D03*
Y1272165D03*
Y1312165D03*
Y1302165D03*
Y1292165D03*
Y1332165D03*
Y1322165D03*
Y1362165D03*
Y1352165D03*
Y1342165D03*
Y1372165D03*
Y1620197D03*
Y1610197D03*
Y1650197D03*
Y1640197D03*
Y1630197D03*
Y1670197D03*
Y1660197D03*
Y1700197D03*
Y1690197D03*
Y1680197D03*
Y1720197D03*
Y1710197D03*
Y1958228D03*
Y1988228D03*
Y1978228D03*
Y1968228D03*
Y2008228D03*
Y1998228D03*
Y2038228D03*
Y2028228D03*
Y2018228D03*
Y2058228D03*
Y2048228D03*
Y2068228D03*
G54D31*
X203542Y73105D03*
X204069Y152050D03*
X204137Y247568D03*
X204597Y331786D03*
X203541Y421732D03*
X204333Y506517D03*
X206668Y598130D03*
X204596Y681645D03*
X205626Y774526D03*
X205386Y856244D03*
X210091Y947202D03*
X209296Y1032544D03*
X205030Y1122856D03*
X205122Y1206233D03*
X205626Y1299104D03*
X204332Y1380966D03*
X203243Y1474162D03*
X204859Y1557277D03*
X205923Y1648177D03*
X205387Y1731351D03*
X205310Y1823227D03*
X204069Y1900420D03*
X205905Y1998730D03*
X205310Y2043388D03*
G54D22*
X45056Y1685410D03*
Y1701945D03*
Y1735016D03*
Y1751551D03*
Y1784622D03*
Y1801158D03*
%LPC*%
G75*
G54D36*
G01X-723776Y2987387D02*
Y-376795D01*
Y-489221D01*
X1782976D01*
Y-376795D01*
Y2987387D01*
X-723776D01*
G01X-4000Y-62500D02*
Y-137500D01*
X496000D01*
Y-62500D01*
X-4000D01*
G01X8000Y-127500D02*
Y-132500D01*
G01X6543Y-127500D02*
X9457D01*
G01X14367Y-132500D02*
X11833D01*
Y-127500D01*
X14367D01*
G01X13353Y-129917D02*
X11833D01*
G01X16933Y-127500D02*
Y-132500D01*
X19467D01*
G01X23300Y-132667D02*
X23173Y-132583D01*
Y-132417D01*
X23300Y-132333D01*
X23427Y-132417D01*
Y-132583D01*
X23300Y-132667D01*
G01Y-130417D02*
X23173Y-130333D01*
Y-130167D01*
X23300Y-130083D01*
X23427Y-130167D01*
Y-130333D01*
X23300Y-130417D01*
G01X28083Y-134167D02*
X27450Y-133333D01*
X27133Y-132500D01*
Y-129167D01*
X27450Y-128333D01*
X28083Y-127500D01*
G01X33500D02*
X32993Y-127667D01*
X32613Y-128083D01*
X32360Y-128583D01*
X32170Y-129250D01*
X32107Y-130000D01*
X32170Y-130750D01*
X32360Y-131417D01*
X32613Y-131917D01*
X32993Y-132333D01*
X33500Y-132500D01*
X34007Y-132333D01*
X34387Y-131917D01*
X34640Y-131417D01*
X34830Y-130750D01*
X34893Y-130000D01*
X34830Y-129250D01*
X34640Y-128583D01*
X34387Y-128083D01*
X34007Y-127667D01*
X33500Y-127500D01*
G01X37207Y-131500D02*
X37587Y-132083D01*
X38093Y-132417D01*
X38663Y-132500D01*
X39170Y-132417D01*
X39677Y-132000D01*
X39993Y-131500D01*
X40057Y-131000D01*
X39930Y-130417D01*
X39487Y-130000D01*
X39043Y-129833D01*
X38473D01*
G01X39043D02*
X39423Y-129583D01*
X39740Y-129167D01*
X39867Y-128667D01*
X39740Y-128167D01*
X39423Y-127750D01*
X38853Y-127500D01*
X38283Y-127583D01*
X37713Y-127917D01*
G01X44017Y-134167D02*
X44650Y-133333D01*
X44967Y-132500D01*
Y-129167D01*
X44650Y-128333D01*
X44017Y-127500D01*
G01X47407Y-131500D02*
X47787Y-132083D01*
X48293Y-132417D01*
X48863Y-132500D01*
X49370Y-132417D01*
X49877Y-132000D01*
X50193Y-131500D01*
X50257Y-131000D01*
X50130Y-130417D01*
X49687Y-130000D01*
X49243Y-129833D01*
X48673D01*
G01X49243D02*
X49623Y-129583D01*
X49940Y-129167D01*
X50067Y-128667D01*
X49940Y-128167D01*
X49623Y-127750D01*
X49053Y-127500D01*
X48483Y-127583D01*
X47913Y-127917D01*
G01X52697Y-128333D02*
X53077Y-127833D01*
X53520Y-127583D01*
X54027Y-127500D01*
X54660Y-127667D01*
X55103Y-128083D01*
X55230Y-128583D01*
X55167Y-129083D01*
X54913Y-129500D01*
X53647Y-130333D01*
X53077Y-130917D01*
X52697Y-131750D01*
X52570Y-132500D01*
X55230D01*
G01X58873D02*
X59000Y-131417D01*
X59190Y-130500D01*
X59443Y-129667D01*
X59760Y-128750D01*
X60267Y-127500D01*
X57733D01*
G01X63277Y-130833D02*
X64923D01*
G01X67997Y-128333D02*
X68377Y-127833D01*
X68820Y-127583D01*
X69327Y-127500D01*
X69960Y-127667D01*
X70403Y-128083D01*
X70530Y-128583D01*
X70467Y-129083D01*
X70213Y-129500D01*
X68947Y-130333D01*
X68377Y-130917D01*
X67997Y-131750D01*
X67870Y-132500D01*
X70530D01*
G01X72907Y-131500D02*
X73287Y-132083D01*
X73793Y-132417D01*
X74363Y-132500D01*
X74870Y-132417D01*
X75377Y-132000D01*
X75693Y-131500D01*
X75757Y-131000D01*
X75630Y-130417D01*
X75187Y-130000D01*
X74743Y-129833D01*
X74173D01*
G01X74743D02*
X75123Y-129583D01*
X75440Y-129167D01*
X75567Y-128667D01*
X75440Y-128167D01*
X75123Y-127750D01*
X74553Y-127500D01*
X73983Y-127583D01*
X73413Y-127917D01*
G01X80160Y-132500D02*
Y-127500D01*
X77817Y-131083D01*
X80983D01*
G01X83107Y-131750D02*
X83487Y-132167D01*
X83930Y-132417D01*
X84500Y-132500D01*
X85070Y-132333D01*
X85513Y-132000D01*
X85830Y-131417D01*
X85893Y-130750D01*
X85767Y-130083D01*
X85450Y-129667D01*
X85007Y-129333D01*
X84563Y-129250D01*
X84120Y-129333D01*
X83550Y-129667D01*
X83740Y-127500D01*
X85450D01*
G01X93497Y-132500D02*
Y-127500D01*
X95903D01*
G01X95017Y-129917D02*
X93497D01*
G01X98217Y-132500D02*
X99800Y-127500D01*
X101383Y-132500D01*
G01X100813Y-130750D02*
X98787D01*
G01X103570Y-132500D02*
X106230Y-127500D01*
G01X103570D02*
X106230Y-132500D01*
G01X110000Y-132667D02*
X109873Y-132583D01*
Y-132417D01*
X110000Y-132333D01*
X110127Y-132417D01*
Y-132583D01*
X110000Y-132667D01*
G01Y-130417D02*
X109873Y-130333D01*
Y-130167D01*
X110000Y-130083D01*
X110127Y-130167D01*
Y-130333D01*
X110000Y-130417D01*
G01X114783Y-134167D02*
X114150Y-133333D01*
X113833Y-132500D01*
Y-129167D01*
X114150Y-128333D01*
X114783Y-127500D01*
G01X120200D02*
X119693Y-127667D01*
X119313Y-128083D01*
X119060Y-128583D01*
X118870Y-129250D01*
X118807Y-130000D01*
X118870Y-130750D01*
X119060Y-131417D01*
X119313Y-131917D01*
X119693Y-132333D01*
X120200Y-132500D01*
X120707Y-132333D01*
X121087Y-131917D01*
X121340Y-131417D01*
X121530Y-130750D01*
X121593Y-130000D01*
X121530Y-129250D01*
X121340Y-128583D01*
X121087Y-128083D01*
X120707Y-127667D01*
X120200Y-127500D01*
G01X123907Y-131500D02*
X124287Y-132083D01*
X124793Y-132417D01*
X125363Y-132500D01*
X125870Y-132417D01*
X126377Y-132000D01*
X126693Y-131500D01*
X126757Y-131000D01*
X126630Y-130417D01*
X126187Y-130000D01*
X125743Y-129833D01*
X125173D01*
G01X125743D02*
X126123Y-129583D01*
X126440Y-129167D01*
X126567Y-128667D01*
X126440Y-128167D01*
X126123Y-127750D01*
X125553Y-127500D01*
X124983Y-127583D01*
X124413Y-127917D01*
G01X130717Y-134167D02*
X131350Y-133333D01*
X131667Y-132500D01*
Y-129167D01*
X131350Y-128333D01*
X130717Y-127500D01*
G01X134107Y-131500D02*
X134487Y-132083D01*
X134993Y-132417D01*
X135563Y-132500D01*
X136070Y-132417D01*
X136577Y-132000D01*
X136893Y-131500D01*
X136957Y-131000D01*
X136830Y-130417D01*
X136387Y-130000D01*
X135943Y-129833D01*
X135373D01*
G01X135943D02*
X136323Y-129583D01*
X136640Y-129167D01*
X136767Y-128667D01*
X136640Y-128167D01*
X136323Y-127750D01*
X135753Y-127500D01*
X135183Y-127583D01*
X134613Y-127917D01*
G01X139523Y-131917D02*
X139967Y-132333D01*
X140473Y-132500D01*
X140980Y-132333D01*
X141423Y-131833D01*
X141740Y-131083D01*
X141867Y-130333D01*
Y-129417D01*
X141740Y-128667D01*
X141423Y-128000D01*
X141043Y-127667D01*
X140600Y-127500D01*
X140093Y-127667D01*
X139713Y-128000D01*
X139460Y-128500D01*
X139333Y-129167D01*
X139460Y-129750D01*
X139777Y-130333D01*
X140157Y-130667D01*
X140600Y-130750D01*
X141107Y-130583D01*
X141487Y-130167D01*
X141867Y-129417D01*
G01X145573Y-132500D02*
X145700Y-131417D01*
X145890Y-130500D01*
X146143Y-129667D01*
X146460Y-128750D01*
X146967Y-127500D01*
X144433D01*
G01X149977Y-130833D02*
X151623D01*
G01X154507Y-131500D02*
X154887Y-132083D01*
X155393Y-132417D01*
X155963Y-132500D01*
X156470Y-132417D01*
X156977Y-132000D01*
X157293Y-131500D01*
X157357Y-131000D01*
X157230Y-130417D01*
X156787Y-130000D01*
X156343Y-129833D01*
X155773D01*
G01X156343D02*
X156723Y-129583D01*
X157040Y-129167D01*
X157167Y-128667D01*
X157040Y-128167D01*
X156723Y-127750D01*
X156153Y-127500D01*
X155583Y-127583D01*
X155013Y-127917D01*
G01X159797Y-130417D02*
X160240Y-129833D01*
X160620Y-129500D01*
X161127Y-129333D01*
X161570Y-129500D01*
X161887Y-129833D01*
X162140Y-130333D01*
X162203Y-130917D01*
X162140Y-131417D01*
X161887Y-131917D01*
X161507Y-132333D01*
X161063Y-132500D01*
X160557Y-132333D01*
X160113Y-131833D01*
X159860Y-131083D01*
X159797Y-130250D01*
X159923Y-129167D01*
X160113Y-128583D01*
X160430Y-128000D01*
X160873Y-127583D01*
X161317Y-127500D01*
X161760Y-127667D01*
X162077Y-128083D01*
G01X166100Y-132500D02*
Y-127500D01*
X165340Y-128500D01*
G01Y-132500D02*
X166860D01*
G01X171960D02*
Y-127500D01*
X169617Y-131083D01*
X172783D01*
G01X191000Y-62500D02*
Y-137500D01*
G01Y-112500D02*
X294000D01*
Y-87500D01*
G01X191000D02*
X294000D01*
G01X301507Y-122500D02*
Y-117500D01*
X302773D01*
X303280Y-117750D01*
X303660Y-118083D01*
X303977Y-118583D01*
X304230Y-119167D01*
X304293Y-120000D01*
X304230Y-120833D01*
X303977Y-121417D01*
X303660Y-121917D01*
X303280Y-122250D01*
X302773Y-122500D01*
X301507D01*
G01X306417D02*
X308000Y-117500D01*
X309583Y-122500D01*
G01X309013Y-120750D02*
X306987D01*
G01X313100Y-117500D02*
Y-122500D01*
G01X311643Y-117500D02*
X314557D01*
G01X319467Y-122500D02*
X316933D01*
Y-117500D01*
X319467D01*
G01X318453Y-119917D02*
X316933D01*
G01X323300Y-122667D02*
X323173Y-122583D01*
Y-122417D01*
X323300Y-122333D01*
X323427Y-122417D01*
Y-122583D01*
X323300Y-122667D01*
G01Y-120417D02*
X323173Y-120333D01*
Y-120167D01*
X323300Y-120083D01*
X323427Y-120167D01*
Y-120333D01*
X323300Y-120417D01*
G01X296000Y-62500D02*
Y-137500D01*
G01X294000Y-62500D02*
Y-137500D01*
G01X301633Y-97500D02*
Y-92500D01*
X303153D01*
X303660Y-92750D01*
X304040Y-93333D01*
X304167Y-94000D01*
X304040Y-94667D01*
X303723Y-95167D01*
X303153Y-95417D01*
X301633D01*
G01X306860Y-97667D02*
X309140Y-92500D01*
G01X311643Y-97500D02*
Y-92500D01*
X314557Y-97500D01*
Y-92500D01*
G01X318200Y-97667D02*
X318073Y-97583D01*
Y-97417D01*
X318200Y-97333D01*
X318327Y-97417D01*
Y-97583D01*
X318200Y-97667D01*
G01Y-95417D02*
X318073Y-95333D01*
Y-95167D01*
X318200Y-95083D01*
X318327Y-95167D01*
Y-95333D01*
X318200Y-95417D01*
G01X296000Y-112500D02*
X496000D01*
G01X301633Y-72500D02*
Y-67500D01*
X303153D01*
X303660Y-67750D01*
X304040Y-68333D01*
X304167Y-69000D01*
X304040Y-69667D01*
X303723Y-70167D01*
X303153Y-70417D01*
X301633D01*
G01X306733Y-72500D02*
Y-67500D01*
X308317D01*
X308823Y-67750D01*
X309140Y-68083D01*
X309267Y-68750D01*
X309140Y-69417D01*
X308760Y-69833D01*
X308317Y-70083D01*
X306733D01*
G01X308317D02*
X309267Y-72500D01*
G01X313100D02*
X312593Y-72417D01*
X312150Y-72083D01*
X311770Y-71583D01*
X311517Y-71000D01*
X311390Y-70333D01*
Y-69667D01*
X311517Y-69000D01*
X311770Y-68417D01*
X312150Y-67917D01*
X312593Y-67583D01*
X313100Y-67500D01*
X313607Y-67583D01*
X314050Y-67917D01*
X314430Y-68417D01*
X314683Y-69000D01*
X314810Y-69667D01*
Y-70333D01*
X314683Y-71000D01*
X314430Y-71583D01*
X314050Y-72083D01*
X313607Y-72417D01*
X313100Y-72500D01*
G01X316933Y-71500D02*
X317250Y-72000D01*
X317630Y-72333D01*
X318073Y-72500D01*
X318580Y-72333D01*
X318960Y-72000D01*
X319340Y-71500D01*
X319467Y-70833D01*
Y-67500D01*
G01X324567Y-72500D02*
X322033D01*
Y-67500D01*
X324567D01*
G01X323553Y-69917D02*
X322033D01*
G01X329793Y-67917D02*
X329413Y-67667D01*
X328970Y-67500D01*
X328463D01*
X327893Y-67750D01*
X327450Y-68167D01*
X327133Y-68667D01*
X326880Y-69500D01*
X326817Y-70250D01*
X326943Y-71000D01*
X327133Y-71500D01*
X327513Y-72000D01*
X327957Y-72333D01*
X328400Y-72500D01*
X328843D01*
X329287Y-72333D01*
X329667Y-72083D01*
X329983Y-71750D01*
G01X333500Y-67500D02*
Y-72500D01*
G01X332043Y-67500D02*
X334957D01*
G01X338600Y-72667D02*
X338473Y-72583D01*
Y-72417D01*
X338600Y-72333D01*
X338727Y-72417D01*
Y-72583D01*
X338600Y-72667D01*
G01Y-70417D02*
X338473Y-70333D01*
Y-70167D01*
X338600Y-70083D01*
X338727Y-70167D01*
Y-70333D01*
X338600Y-70417D01*
G01X296000Y-87500D02*
X496000D01*
G01X411000Y-112500D02*
Y-137500D01*
G01X416633Y-122500D02*
Y-117500D01*
X418217D01*
X418723Y-117750D01*
X419040Y-118083D01*
X419167Y-118750D01*
X419040Y-119417D01*
X418660Y-119833D01*
X418217Y-120083D01*
X416633D01*
G01X418217D02*
X419167Y-122500D01*
G01X424267D02*
X421733D01*
Y-117500D01*
X424267D01*
G01X423253Y-119917D02*
X421733D01*
G01X426517Y-117500D02*
X428100Y-122500D01*
X429683Y-117500D01*
G01X433200Y-122667D02*
X433073Y-122583D01*
Y-122417D01*
X433200Y-122333D01*
X433327Y-122417D01*
Y-122583D01*
X433200Y-122667D01*
G01Y-120417D02*
X433073Y-120333D01*
Y-120167D01*
X433200Y-120083D01*
X433327Y-120167D01*
Y-120333D01*
X433200Y-120417D01*
G01X460000Y-112500D02*
Y-137500D01*
G01X-723776Y2987387D02*
Y-376795D01*
Y-489221D01*
X1782976D01*
Y-376795D01*
Y2987387D01*
X-723776D01*
G01X6705Y-124160D02*
X7332Y-124685D01*
X8037Y-125000D01*
X8663D01*
X9290Y-124685D01*
X9760Y-124160D01*
X9995Y-123425D01*
X9838Y-122690D01*
X9447Y-122060D01*
X8742Y-121640D01*
X7802Y-121430D01*
X7253Y-121010D01*
X7018Y-120275D01*
X7175Y-119540D01*
X7567Y-119015D01*
X8115Y-118700D01*
X8663D01*
X9212Y-118910D01*
X9682Y-119435D01*
G01X13005Y-125000D02*
Y-118700D01*
G01X16295D02*
Y-125000D01*
G01Y-121850D02*
X13005D01*
G01X20010Y-118700D02*
X21890D01*
G01X20950D02*
Y-125000D01*
G01X20010D02*
X21890D01*
G01X28817D02*
X25683D01*
Y-118700D01*
X28817D01*
G01X27563Y-121745D02*
X25683D01*
G01X31748Y-125000D02*
Y-118700D01*
X35352Y-125000D01*
Y-118700D01*
G01X39693Y-126155D02*
X40007Y-124790D01*
G01X46150Y-118700D02*
Y-125000D01*
G01X44348Y-118700D02*
X47952D01*
G01X50492Y-125000D02*
X52450Y-118700D01*
X54408Y-125000D01*
G01X53703Y-122795D02*
X51197D01*
G01X57810Y-118700D02*
X59690D01*
G01X58750D02*
Y-125000D01*
G01X57810D02*
X59690D01*
G01X62700Y-118700D02*
X63797Y-125000D01*
X65050Y-118700D01*
X66303Y-125000D01*
X67400Y-118700D01*
G01X69392Y-125000D02*
X71350Y-118700D01*
X73308Y-125000D01*
G01X72603Y-122795D02*
X70097D01*
G01X75848Y-125000D02*
Y-118700D01*
X79452Y-125000D01*
Y-118700D01*
G01X88683Y-125000D02*
Y-118700D01*
X90642D01*
X91268Y-119015D01*
X91660Y-119435D01*
X91817Y-120275D01*
X91660Y-121115D01*
X91190Y-121640D01*
X90642Y-121955D01*
X88683D01*
G01X90642D02*
X91817Y-125000D01*
G01X96550Y-125210D02*
X96393Y-125105D01*
Y-124895D01*
X96550Y-124790D01*
X96707Y-124895D01*
Y-125105D01*
X96550Y-125210D01*
G01X102850Y-125000D02*
X102223Y-124895D01*
X101675Y-124475D01*
X101205Y-123845D01*
X100892Y-123110D01*
X100735Y-122270D01*
Y-121430D01*
X100892Y-120590D01*
X101205Y-119855D01*
X101675Y-119225D01*
X102223Y-118805D01*
X102850Y-118700D01*
X103477Y-118805D01*
X104025Y-119225D01*
X104495Y-119855D01*
X104808Y-120590D01*
X104965Y-121430D01*
Y-122270D01*
X104808Y-123110D01*
X104495Y-123845D01*
X104025Y-124475D01*
X103477Y-124895D01*
X102850Y-125000D01*
G01X109150Y-125210D02*
X108993Y-125105D01*
Y-124895D01*
X109150Y-124790D01*
X109307Y-124895D01*
Y-125105D01*
X109150Y-125210D01*
G01X117173Y-119225D02*
X116703Y-118910D01*
X116155Y-118700D01*
X115528D01*
X114823Y-119015D01*
X114275Y-119540D01*
X113883Y-120170D01*
X113570Y-121220D01*
X113492Y-122165D01*
X113648Y-123110D01*
X113883Y-123740D01*
X114353Y-124370D01*
X114902Y-124790D01*
X115450Y-125000D01*
X115998D01*
X116547Y-124790D01*
X117017Y-124475D01*
X117408Y-124055D01*
G01X121750Y-125210D02*
X121593Y-125105D01*
Y-124895D01*
X121750Y-124790D01*
X121907Y-124895D01*
Y-125105D01*
X121750Y-125210D01*
G01X6627Y-115000D02*
Y-108700D01*
G01X9603D02*
X6627Y-112585D01*
G01X10073Y-115000D02*
X7958Y-110800D01*
G01X12927Y-108700D02*
Y-113215D01*
X13240Y-114160D01*
X13867Y-114790D01*
X14650Y-115000D01*
X15433Y-114790D01*
X16060Y-114160D01*
X16373Y-113215D01*
Y-108700D01*
G01X22517Y-115000D02*
X19383D01*
Y-108700D01*
X22517D01*
G01X21263Y-111745D02*
X19383D01*
G01X26310Y-108700D02*
X28190D01*
G01X27250D02*
Y-115000D01*
G01X26310D02*
X28190D01*
G01X38205Y-114160D02*
X38832Y-114685D01*
X39537Y-115000D01*
X40163D01*
X40790Y-114685D01*
X41260Y-114160D01*
X41495Y-113425D01*
X41338Y-112690D01*
X40947Y-112060D01*
X40242Y-111640D01*
X39302Y-111430D01*
X38753Y-111010D01*
X38518Y-110275D01*
X38675Y-109540D01*
X39067Y-109015D01*
X39615Y-108700D01*
X40163D01*
X40712Y-108910D01*
X41182Y-109435D01*
G01X44505Y-115000D02*
Y-108700D01*
G01X47795D02*
Y-115000D01*
G01Y-111850D02*
X44505D01*
G01X50492Y-115000D02*
X52450Y-108700D01*
X54408Y-115000D01*
G01X53703Y-112795D02*
X51197D01*
G01X56948Y-115000D02*
Y-108700D01*
X60552Y-115000D01*
Y-108700D01*
G01X69705Y-115000D02*
Y-108700D01*
G01X72995D02*
Y-115000D01*
G01Y-111850D02*
X69705D01*
G01X76005Y-114160D02*
X76632Y-114685D01*
X77337Y-115000D01*
X77963D01*
X78590Y-114685D01*
X79060Y-114160D01*
X79295Y-113425D01*
X79138Y-112690D01*
X78747Y-112060D01*
X78042Y-111640D01*
X77102Y-111430D01*
X76553Y-111010D01*
X76318Y-110275D01*
X76475Y-109540D01*
X76867Y-109015D01*
X77415Y-108700D01*
X77963D01*
X78512Y-108910D01*
X78982Y-109435D01*
G01X83010Y-108700D02*
X84890D01*
G01X83950D02*
Y-115000D01*
G01X83010D02*
X84890D01*
G01X88292D02*
X90250Y-108700D01*
X92208Y-115000D01*
G01X91503Y-112795D02*
X88997D01*
G01X94748Y-115000D02*
Y-108700D01*
X98352Y-115000D01*
Y-108700D01*
G01X103320Y-111850D02*
X104887D01*
Y-113740D01*
X104417Y-114370D01*
X103868Y-114790D01*
X103085Y-115000D01*
X102302Y-114790D01*
X101753Y-114370D01*
X101283Y-113740D01*
X100970Y-113005D01*
X100813Y-112165D01*
Y-111430D01*
X100970Y-110800D01*
X101283Y-110065D01*
X101753Y-109435D01*
X102223Y-109015D01*
X102850Y-108700D01*
X103398D01*
X104025Y-108910D01*
X104495Y-109330D01*
G01X108993Y-116155D02*
X109307Y-114790D01*
G01X115450Y-108700D02*
Y-115000D01*
G01X113648Y-108700D02*
X117252D01*
G01X119792Y-115000D02*
X121750Y-108700D01*
X123708Y-115000D01*
G01X123003Y-112795D02*
X120497D01*
G01X128050Y-115000D02*
X127423Y-114895D01*
X126875Y-114475D01*
X126405Y-113845D01*
X126092Y-113110D01*
X125935Y-112270D01*
Y-111430D01*
X126092Y-110590D01*
X126405Y-109855D01*
X126875Y-109225D01*
X127423Y-108805D01*
X128050Y-108700D01*
X128677Y-108805D01*
X129225Y-109225D01*
X129695Y-109855D01*
X130008Y-110590D01*
X130165Y-111430D01*
Y-112270D01*
X130008Y-113110D01*
X129695Y-113845D01*
X129225Y-114475D01*
X128677Y-114895D01*
X128050Y-115000D01*
G01X140650D02*
Y-112165D01*
X139083Y-108700D01*
G01X142217D02*
X140650Y-112165D01*
G01X145227Y-108700D02*
Y-113215D01*
X145540Y-114160D01*
X146167Y-114790D01*
X146950Y-115000D01*
X147733Y-114790D01*
X148360Y-114160D01*
X148673Y-113215D01*
Y-108700D01*
G01X151292Y-115000D02*
X153250Y-108700D01*
X155208Y-115000D01*
G01X154503Y-112795D02*
X151997D01*
G01X157748Y-115000D02*
Y-108700D01*
X161352Y-115000D01*
Y-108700D01*
G01X30650Y-92300D02*
X28130Y-91883D01*
X25925Y-90217D01*
X24035Y-87717D01*
X22775Y-84800D01*
X22145Y-81467D01*
Y-78133D01*
X22775Y-74800D01*
X24035Y-71883D01*
X25925Y-69384D01*
X28130Y-67717D01*
X30650Y-67300D01*
X33170Y-67717D01*
X35375Y-69384D01*
X37265Y-71883D01*
X38525Y-74800D01*
X39155Y-78133D01*
Y-81467D01*
X38525Y-84800D01*
X37265Y-87717D01*
X35375Y-90217D01*
X33170Y-91883D01*
X30650Y-92300D01*
G01X33170Y-85633D02*
X36950Y-92300D01*
G01X50495Y-75634D02*
Y-87300D01*
X51755Y-90217D01*
X53645Y-91883D01*
X55850Y-92300D01*
X58055Y-91883D01*
X59945Y-90217D01*
X61205Y-87300D01*
G01Y-92300D02*
Y-75634D01*
G01X86720Y-92300D02*
Y-75634D01*
G01Y-78550D02*
X85460Y-76884D01*
X83570Y-76050D01*
X81365Y-75634D01*
X79160Y-76467D01*
X77270Y-78133D01*
X76010Y-80634D01*
X75380Y-83967D01*
X76010Y-87300D01*
X77270Y-89801D01*
X79160Y-91467D01*
X81365Y-92300D01*
X83570Y-91883D01*
X85460Y-90634D01*
X86720Y-88967D01*
G01X100895Y-92300D02*
Y-75634D01*
G01Y-79800D02*
X102155Y-77717D01*
X104045Y-76050D01*
X106565Y-75634D01*
X108770Y-76050D01*
X110660Y-77717D01*
X111605Y-80634D01*
Y-92300D01*
G01X131450Y-67300D02*
Y-92300D01*
G01X127040Y-75634D02*
X135860D01*
G01X162320Y-92300D02*
Y-75634D01*
G01Y-78550D02*
X161060Y-76884D01*
X159170Y-76050D01*
X156965Y-75634D01*
X154760Y-76467D01*
X152870Y-78133D01*
X151610Y-80634D01*
X150980Y-83967D01*
X151610Y-87300D01*
X152870Y-89801D01*
X154760Y-91467D01*
X156965Y-92300D01*
X159170Y-91883D01*
X161060Y-90634D01*
X162320Y-88967D01*
G01X6548Y-105000D02*
Y-98700D01*
X10152Y-105000D01*
Y-98700D01*
G01X14650Y-105000D02*
X14023Y-104895D01*
X13475Y-104475D01*
X13005Y-103845D01*
X12692Y-103110D01*
X12535Y-102270D01*
Y-101430D01*
X12692Y-100590D01*
X13005Y-99855D01*
X13475Y-99225D01*
X14023Y-98805D01*
X14650Y-98700D01*
X15277Y-98805D01*
X15825Y-99225D01*
X16295Y-99855D01*
X16608Y-100590D01*
X16765Y-101430D01*
Y-102270D01*
X16608Y-103110D01*
X16295Y-103845D01*
X15825Y-104475D01*
X15277Y-104895D01*
X14650Y-105000D01*
G01X20950Y-105210D02*
X20793Y-105105D01*
Y-104895D01*
X20950Y-104790D01*
X21107Y-104895D01*
Y-105105D01*
X20950Y-105210D01*
G01X27250Y-105000D02*
Y-98700D01*
X26310Y-99960D01*
G01Y-105000D02*
X28190D01*
G01X33550D02*
X34098Y-104895D01*
X34725Y-104580D01*
X35117Y-104055D01*
X35273Y-103320D01*
X35117Y-102585D01*
X34647Y-101955D01*
X33942Y-101640D01*
X33158D01*
X32688Y-101430D01*
X32297Y-100905D01*
X32140Y-100170D01*
X32375Y-99435D01*
X32923Y-98910D01*
X33550Y-98700D01*
X34177Y-98910D01*
X34725Y-99435D01*
X34960Y-100170D01*
X34803Y-100905D01*
X34412Y-101430D01*
X33942Y-101640D01*
X33158D01*
X32453Y-101955D01*
X31983Y-102585D01*
X31827Y-103320D01*
X31983Y-104055D01*
X32375Y-104580D01*
X33002Y-104895D01*
X33550Y-105000D01*
G01X39850D02*
X40398Y-104895D01*
X41025Y-104580D01*
X41417Y-104055D01*
X41573Y-103320D01*
X41417Y-102585D01*
X40947Y-101955D01*
X40242Y-101640D01*
X39458D01*
X38988Y-101430D01*
X38597Y-100905D01*
X38440Y-100170D01*
X38675Y-99435D01*
X39223Y-98910D01*
X39850Y-98700D01*
X40477Y-98910D01*
X41025Y-99435D01*
X41260Y-100170D01*
X41103Y-100905D01*
X40712Y-101430D01*
X40242Y-101640D01*
X39458D01*
X38753Y-101955D01*
X38283Y-102585D01*
X38127Y-103320D01*
X38283Y-104055D01*
X38675Y-104580D01*
X39302Y-104895D01*
X39850Y-105000D01*
G01X45993Y-106155D02*
X46307Y-104790D01*
G01X50100Y-98700D02*
X51197Y-105000D01*
X52450Y-98700D01*
X53703Y-105000D01*
X54800Y-98700D01*
G01X60317Y-105000D02*
X57183D01*
Y-98700D01*
X60317D01*
G01X59063Y-101745D02*
X57183D01*
G01X63248Y-105000D02*
Y-98700D01*
X66852Y-105000D01*
Y-98700D01*
G01X76005Y-105000D02*
Y-98700D01*
G01X79295D02*
Y-105000D01*
G01Y-101850D02*
X76005D01*
G01X81600Y-98700D02*
X82697Y-105000D01*
X83950Y-98700D01*
X85203Y-105000D01*
X86300Y-98700D01*
G01X88292Y-105000D02*
X90250Y-98700D01*
X92208Y-105000D01*
G01X91503Y-102795D02*
X88997D01*
G01X101362Y-99750D02*
X101832Y-99120D01*
X102380Y-98805D01*
X103007Y-98700D01*
X103790Y-98910D01*
X104338Y-99435D01*
X104495Y-100065D01*
X104417Y-100695D01*
X104103Y-101220D01*
X102537Y-102270D01*
X101832Y-103005D01*
X101362Y-104055D01*
X101205Y-105000D01*
X104495D01*
G01X107348D02*
Y-98700D01*
X110952Y-105000D01*
Y-98700D01*
G01X113727Y-105000D02*
Y-98700D01*
X115293D01*
X115920Y-99015D01*
X116390Y-99435D01*
X116782Y-100065D01*
X117095Y-100800D01*
X117173Y-101850D01*
X117095Y-102900D01*
X116782Y-103635D01*
X116390Y-104265D01*
X115920Y-104685D01*
X115293Y-105000D01*
X113727D01*
G01X126483D02*
Y-98700D01*
X128442D01*
X129068Y-99015D01*
X129460Y-99435D01*
X129617Y-100275D01*
X129460Y-101115D01*
X128990Y-101640D01*
X128442Y-101955D01*
X126483D01*
G01X128442D02*
X129617Y-105000D01*
G01X132627D02*
Y-98700D01*
X134193D01*
X134820Y-99015D01*
X135290Y-99435D01*
X135682Y-100065D01*
X135995Y-100800D01*
X136073Y-101850D01*
X135995Y-102900D01*
X135682Y-103635D01*
X135290Y-104265D01*
X134820Y-104685D01*
X134193Y-105000D01*
X132627D01*
G01X140650Y-105210D02*
X140493Y-105105D01*
Y-104895D01*
X140650Y-104790D01*
X140807Y-104895D01*
Y-105105D01*
X140650Y-105210D01*
G01X202000Y-72000D02*
Y-80000D01*
X206000D01*
G01X213800D02*
Y-74667D01*
G01Y-75600D02*
X213400Y-75067D01*
X212800Y-74800D01*
X212100Y-74667D01*
X211400Y-74933D01*
X210800Y-75467D01*
X210400Y-76267D01*
X210200Y-77333D01*
X210400Y-78400D01*
X210800Y-79200D01*
X211400Y-79733D01*
X212100Y-80000D01*
X212800Y-79867D01*
X213400Y-79467D01*
X213800Y-78934D01*
G01X217900Y-82400D02*
X218500Y-82667D01*
X219300Y-82400D01*
X219800Y-81867D01*
X220200Y-81200D01*
X220800Y-79067D01*
X222100Y-74667D01*
G01X218900D02*
X220800Y-79067D01*
G01X226500Y-76400D02*
X229700D01*
X229400Y-75467D01*
X228900Y-74933D01*
X228200Y-74667D01*
X227500Y-74800D01*
X226900Y-75200D01*
X226500Y-76133D01*
X226300Y-76934D01*
Y-77733D01*
X226500Y-78533D01*
X227000Y-79333D01*
X227600Y-79867D01*
X228300Y-80000D01*
X229000Y-79733D01*
X229700Y-78934D01*
G01X234600Y-80000D02*
Y-74667D01*
G01Y-75733D02*
X235100Y-75200D01*
X235600Y-74800D01*
X236300Y-74667D01*
X236800Y-74800D01*
X237400Y-75200D01*
G01X225500Y-122000D02*
Y-130000D01*
G01X223200Y-122000D02*
X227800D01*
G01X233500Y-124667D02*
Y-130000D01*
G01Y-122533D02*
X233300Y-122400D01*
Y-122133D01*
X233500Y-122000D01*
X233700Y-122133D01*
Y-122400D01*
X233500Y-122533D01*
G01X239800Y-130000D02*
Y-124667D01*
G01Y-126000D02*
X240200Y-125333D01*
X240800Y-124800D01*
X241600Y-124667D01*
X242300Y-124800D01*
X242900Y-125333D01*
X243200Y-126267D01*
Y-130000D01*
G01X251300D02*
Y-124667D01*
G01Y-125600D02*
X250900Y-125067D01*
X250300Y-124800D01*
X249600Y-124667D01*
X248900Y-124933D01*
X248300Y-125467D01*
X247900Y-126267D01*
X247700Y-127333D01*
X247900Y-128400D01*
X248300Y-129200D01*
X248900Y-129733D01*
X249600Y-130000D01*
X250300Y-129867D01*
X250900Y-129467D01*
X251300Y-128934D01*
G01X230500Y-97000D02*
X233000Y-105000D01*
X235500Y-97000D01*
G01X243200Y-97667D02*
X242600Y-97267D01*
X241900Y-97000D01*
X241100D01*
X240200Y-97400D01*
X239500Y-98067D01*
X239000Y-98867D01*
X238600Y-100200D01*
X238500Y-101400D01*
X238700Y-102600D01*
X239000Y-103400D01*
X239600Y-104200D01*
X240300Y-104733D01*
X241000Y-105000D01*
X241700D01*
X242400Y-104733D01*
X243000Y-104333D01*
X243500Y-103800D01*
G01X251200Y-97667D02*
X250600Y-97267D01*
X249900Y-97000D01*
X249100D01*
X248200Y-97400D01*
X247500Y-98067D01*
X247000Y-98867D01*
X246600Y-100200D01*
X246500Y-101400D01*
X246700Y-102600D01*
X247000Y-103400D01*
X247600Y-104200D01*
X248300Y-104733D01*
X249000Y-105000D01*
X249700D01*
X250400Y-104733D01*
X251000Y-104333D01*
X251500Y-103800D01*
G01X256700Y-80000D02*
Y-72000D01*
X253000Y-77733D01*
X258000D01*
G01X328600Y-123333D02*
X329200Y-122533D01*
X329900Y-122133D01*
X330700Y-122000D01*
X331700Y-122267D01*
X332400Y-122933D01*
X332600Y-123733D01*
X332500Y-124534D01*
X332100Y-125200D01*
X330100Y-126533D01*
X329200Y-127467D01*
X328600Y-128800D01*
X328400Y-130000D01*
X332600D01*
G01X338500Y-122000D02*
X337700Y-122267D01*
X337100Y-122933D01*
X336700Y-123733D01*
X336400Y-124800D01*
X336300Y-126000D01*
X336400Y-127200D01*
X336700Y-128267D01*
X337100Y-129067D01*
X337700Y-129733D01*
X338500Y-130000D01*
X339300Y-129733D01*
X339900Y-129067D01*
X340300Y-128267D01*
X340600Y-127200D01*
X340700Y-126000D01*
X340600Y-124800D01*
X340300Y-123733D01*
X339900Y-122933D01*
X339300Y-122267D01*
X338500Y-122000D01*
G01X346500Y-130000D02*
Y-122000D01*
X345300Y-123600D01*
G01Y-130000D02*
X347700D01*
G01X352300Y-128400D02*
X352900Y-129333D01*
X353700Y-129867D01*
X354600Y-130000D01*
X355400Y-129867D01*
X356200Y-129200D01*
X356700Y-128400D01*
X356800Y-127600D01*
X356600Y-126667D01*
X355900Y-126000D01*
X355200Y-125733D01*
X354300D01*
G01X355200D02*
X355800Y-125333D01*
X356300Y-124667D01*
X356500Y-123867D01*
X356300Y-123067D01*
X355800Y-122400D01*
X354900Y-122000D01*
X354000Y-122133D01*
X353100Y-122667D01*
G01X360700Y-130267D02*
X364300Y-122000D01*
G01X370500D02*
X369700Y-122267D01*
X369100Y-122933D01*
X368700Y-123733D01*
X368400Y-124800D01*
X368300Y-126000D01*
X368400Y-127200D01*
X368700Y-128267D01*
X369100Y-129067D01*
X369700Y-129733D01*
X370500Y-130000D01*
X371300Y-129733D01*
X371900Y-129067D01*
X372300Y-128267D01*
X372600Y-127200D01*
X372700Y-126000D01*
X372600Y-124800D01*
X372300Y-123733D01*
X371900Y-122933D01*
X371300Y-122267D01*
X370500Y-122000D01*
G01X378500Y-130000D02*
Y-122000D01*
X377300Y-123600D01*
G01Y-130000D02*
X379700D01*
G01X384700Y-130267D02*
X388300Y-122000D01*
G01X394500D02*
X393700Y-122267D01*
X393100Y-122933D01*
X392700Y-123733D01*
X392400Y-124800D01*
X392300Y-126000D01*
X392400Y-127200D01*
X392700Y-128267D01*
X393100Y-129067D01*
X393700Y-129733D01*
X394500Y-130000D01*
X395300Y-129733D01*
X395900Y-129067D01*
X396300Y-128267D01*
X396600Y-127200D01*
X396700Y-126000D01*
X396600Y-124800D01*
X396300Y-123733D01*
X395900Y-122933D01*
X395300Y-122267D01*
X394500Y-122000D01*
G01X400800Y-129067D02*
X401500Y-129733D01*
X402300Y-130000D01*
X403100Y-129733D01*
X403800Y-128934D01*
X404300Y-127733D01*
X404500Y-126533D01*
Y-125067D01*
X404300Y-123867D01*
X403800Y-122800D01*
X403200Y-122267D01*
X402500Y-122000D01*
X401700Y-122267D01*
X401100Y-122800D01*
X400700Y-123600D01*
X400500Y-124667D01*
X400700Y-125600D01*
X401200Y-126533D01*
X401800Y-127067D01*
X402500Y-127200D01*
X403300Y-126934D01*
X403900Y-126267D01*
X404500Y-125067D01*
G01X328300Y-105000D02*
Y-97000D01*
X330300D01*
X331100Y-97400D01*
X331700Y-97933D01*
X332200Y-98733D01*
X332600Y-99667D01*
X332700Y-101000D01*
X332600Y-102333D01*
X332200Y-103267D01*
X331700Y-104067D01*
X331100Y-104600D01*
X330300Y-105000D01*
X328300D01*
G01X336000D02*
X338500Y-97000D01*
X341000Y-105000D01*
G01X340100Y-102200D02*
X336900D01*
G01X346500Y-97000D02*
Y-105000D01*
G01X344200Y-97000D02*
X348800D01*
G01X352600Y-101667D02*
X353300Y-100733D01*
X353900Y-100200D01*
X354700Y-99933D01*
X355400Y-100200D01*
X355900Y-100733D01*
X356300Y-101533D01*
X356400Y-102467D01*
X356300Y-103267D01*
X355900Y-104067D01*
X355300Y-104733D01*
X354600Y-105000D01*
X353800Y-104733D01*
X353100Y-103934D01*
X352700Y-102733D01*
X352600Y-101400D01*
X352800Y-99667D01*
X353100Y-98733D01*
X353600Y-97800D01*
X354300Y-97133D01*
X355000Y-97000D01*
X355700Y-97267D01*
X356200Y-97933D01*
G01X359900Y-105000D02*
Y-97000D01*
X362500Y-103667D01*
X365100Y-97000D01*
Y-105000D01*
G01X370500Y-97000D02*
Y-105000D01*
G01X368200Y-97000D02*
X372800D01*
G01X379300Y-100733D02*
X379700Y-100333D01*
X380000Y-99667D01*
X380200Y-98733D01*
X380000Y-97933D01*
X379600Y-97400D01*
X378900Y-97000D01*
X376200D01*
Y-105000D01*
X379500D01*
X380200Y-104467D01*
X380600Y-103667D01*
X380800Y-102733D01*
X380600Y-101800D01*
X380000Y-101000D01*
X379300Y-100733D01*
X376200D01*
G01X386500Y-105000D02*
X387200Y-104867D01*
X388000Y-104467D01*
X388500Y-103800D01*
X388700Y-102867D01*
X388500Y-101934D01*
X387900Y-101133D01*
X387000Y-100733D01*
X386000D01*
X385400Y-100467D01*
X384900Y-99800D01*
X384700Y-98867D01*
X385000Y-97933D01*
X385700Y-97267D01*
X386500Y-97000D01*
X387300Y-97267D01*
X388000Y-97933D01*
X388300Y-98867D01*
X388100Y-99800D01*
X387600Y-100467D01*
X387000Y-100733D01*
X386000D01*
X385100Y-101133D01*
X384500Y-101934D01*
X384300Y-102867D01*
X384500Y-103800D01*
X385000Y-104467D01*
X385800Y-104867D01*
X386500Y-105000D01*
G01X394500D02*
X395200Y-104867D01*
X396000Y-104467D01*
X396500Y-103800D01*
X396700Y-102867D01*
X396500Y-101934D01*
X395900Y-101133D01*
X395000Y-100733D01*
X394000D01*
X393400Y-100467D01*
X392900Y-99800D01*
X392700Y-98867D01*
X393000Y-97933D01*
X393700Y-97267D01*
X394500Y-97000D01*
X395300Y-97267D01*
X396000Y-97933D01*
X396300Y-98867D01*
X396100Y-99800D01*
X395600Y-100467D01*
X395000Y-100733D01*
X394000D01*
X393100Y-101133D01*
X392500Y-101934D01*
X392300Y-102867D01*
X392500Y-103800D01*
X393000Y-104467D01*
X393800Y-104867D01*
X394500Y-105000D01*
G01X400000D02*
X402500Y-97000D01*
X405000Y-105000D01*
G01X404100Y-102200D02*
X400900D01*
G01X410500Y-97000D02*
X409700Y-97267D01*
X409100Y-97933D01*
X408700Y-98733D01*
X408400Y-99800D01*
X408300Y-101000D01*
X408400Y-102200D01*
X408700Y-103267D01*
X409100Y-104067D01*
X409700Y-104733D01*
X410500Y-105000D01*
X411300Y-104733D01*
X411900Y-104067D01*
X412300Y-103267D01*
X412600Y-102200D01*
X412700Y-101000D01*
X412600Y-99800D01*
X412300Y-98733D01*
X411900Y-97933D01*
X411300Y-97267D01*
X410500Y-97000D01*
G01X350500Y-72000D02*
Y-80000D01*
G01X348200Y-72000D02*
X352800D01*
G01X356600Y-76667D02*
X357300Y-75733D01*
X357900Y-75200D01*
X358700Y-74933D01*
X359400Y-75200D01*
X359900Y-75733D01*
X360300Y-76533D01*
X360400Y-77467D01*
X360300Y-78267D01*
X359900Y-79067D01*
X359300Y-79733D01*
X358600Y-80000D01*
X357800Y-79733D01*
X357100Y-78934D01*
X356700Y-77733D01*
X356600Y-76400D01*
X356800Y-74667D01*
X357100Y-73733D01*
X357600Y-72800D01*
X358300Y-72133D01*
X359000Y-72000D01*
X359700Y-72267D01*
X360200Y-72933D01*
G01X363900Y-80000D02*
Y-72000D01*
X366500Y-78667D01*
X369100Y-72000D01*
Y-80000D01*
G01X375100Y-76000D02*
X377100D01*
Y-78400D01*
X376500Y-79200D01*
X375800Y-79733D01*
X374800Y-80000D01*
X373800Y-79733D01*
X373100Y-79200D01*
X372500Y-78400D01*
X372100Y-77467D01*
X371900Y-76400D01*
Y-75467D01*
X372100Y-74667D01*
X372500Y-73733D01*
X373100Y-72933D01*
X373700Y-72400D01*
X374500Y-72000D01*
X375200D01*
X376000Y-72267D01*
X376600Y-72800D01*
G01X379500Y-82667D02*
X385500D01*
G01X388500Y-80000D02*
Y-72000D01*
X390900D01*
X391700Y-72400D01*
X392300Y-73333D01*
X392500Y-74400D01*
X392300Y-75467D01*
X391800Y-76267D01*
X390900Y-76667D01*
X388500D01*
G01X396300Y-80000D02*
Y-72000D01*
X398300D01*
X399100Y-72400D01*
X399700Y-72933D01*
X400200Y-73733D01*
X400600Y-74667D01*
X400700Y-76000D01*
X400600Y-77333D01*
X400200Y-78267D01*
X399700Y-79067D01*
X399100Y-79600D01*
X398300Y-80000D01*
X396300D01*
G01X407300Y-75733D02*
X407700Y-75333D01*
X408000Y-74667D01*
X408200Y-73733D01*
X408000Y-72933D01*
X407600Y-72400D01*
X406900Y-72000D01*
X404200D01*
Y-80000D01*
X407500D01*
X408200Y-79467D01*
X408600Y-78667D01*
X408800Y-77733D01*
X408600Y-76800D01*
X408000Y-76000D01*
X407300Y-75733D01*
X404200D01*
G01X411500Y-82667D02*
X417500D01*
G01X420000Y-80000D02*
X422500Y-72000D01*
X425000Y-80000D01*
G01X424100Y-77200D02*
X420900D01*
G01X427500Y-82667D02*
X433500D01*
G01X439300Y-75733D02*
X439700Y-75333D01*
X440000Y-74667D01*
X440200Y-73733D01*
X440000Y-72933D01*
X439600Y-72400D01*
X438900Y-72000D01*
X436200D01*
Y-80000D01*
X439500D01*
X440200Y-79467D01*
X440600Y-78667D01*
X440800Y-77733D01*
X440600Y-76800D01*
X440000Y-76000D01*
X439300Y-75733D01*
X436200D01*
G01X444300Y-80000D02*
Y-72000D01*
X446300D01*
X447100Y-72400D01*
X447700Y-72933D01*
X448200Y-73733D01*
X448600Y-74667D01*
X448700Y-76000D01*
X448600Y-77333D01*
X448200Y-78267D01*
X447700Y-79067D01*
X447100Y-79600D01*
X446300Y-80000D01*
X444300D01*
G01X443000Y-130000D02*
X445500Y-122000D01*
X448000Y-130000D01*
G01X447100Y-127200D02*
X443900D01*
G01X473000Y-130000D02*
Y-122000D01*
X471800Y-123600D01*
G01Y-130000D02*
X474200D01*
G01X479100Y-126667D02*
X479800Y-125733D01*
X480400Y-125200D01*
X481200Y-124933D01*
X481900Y-125200D01*
X482400Y-125733D01*
X482800Y-126533D01*
X482900Y-127467D01*
X482800Y-128267D01*
X482400Y-129067D01*
X481800Y-129733D01*
X481100Y-130000D01*
X480300Y-129733D01*
X479600Y-128934D01*
X479200Y-127733D01*
X479100Y-126400D01*
X479300Y-124667D01*
X479600Y-123733D01*
X480100Y-122800D01*
X480800Y-122133D01*
X481500Y-122000D01*
X482200Y-122267D01*
X482700Y-122933D01*
M02*
